FILE_TYPE = MACRO_DRAWING;
SET COLOR_WIRE YELLOW;
SET COLOR_PROP ORANGE;
SET COLOR_DOT WHITE;
SET COLOR_ARC YELLOW;
SET COLOR_BODY GREEN;
SET COLOR_NOTE PURPLE;
SET PROP_DISPLAY VALUE;
SET PAGE_NUMBER P199;
FORCEADD UNIVERSAL_GND..1
(-2925 5925);
FORCEPROP 3 LASTPIN (-2925 5975) SIG_NAME GND\g
J 0
(-2915 5985);
DISPLAY 0.659574 (-2915 5985);
PAINT MONO (-2915 5985);
DISPLAY INVISIBLE (-2915 5985);
FORCEPROP 1 LAST HDL_POWER GND
J 1
(-2900 5850);
DISPLAY 0.872340 (-2900 5850);
PAINT GREEN (-2900 5850);
DISPLAY INVISIBLE (-2900 5850);
FORCEPROP 1 LAST PATH I10
J 0
(-2850 5925);
DISPLAY 0.872340 (-2850 5925);
PAINT AQUA (-2850 5925);
DISPLAY INVISIBLE (-2850 5925);
FORCEPROP 2 LAST CDS_LIB pure_quanta_power
J 0
(-2925 5925);
DISPLAY INVISIBLE (-2925 5925);
FORCEADD Q_CAP..1
(-5325 475);
FORCEPROP 1 LAST LOCATION PC8
J 0
(-5275 575);
DISPLAY 0.489362 (-5275 575);
PAINT SKYBLUE (-5275 575);
FORCEPROP 2 LAST SEC 1
J 0
(-5275 675);
DISPLAY 0.680851 (-5275 675);
PAINT MONO (-5275 675);
DISPLAY INVISIBLE (-5275 675);
FORCEPROP 1 LASTPIN (-5325 575) $PN 1
J 0
(-5315 555);
DISPLAY 0.489362 (-5315 555);
PAINT MONO (-5315 555);
FORCEPROP 1 LASTPIN (-5325 375) $PN 2
J 0
(-5315 355);
DISPLAY 0.489362 (-5315 355);
PAINT MONO (-5315 355);
FORCEPROP 1 LAST PACK_TYPE 0402
J 0
(-5275 275);
DISPLAY 0.489362 (-5275 275);
PAINT SKYBLUE (-5275 275);
FORCEPROP 1 LAST VOLTAGE 25V
J 0
(-5275 475);
DISPLAY 0.489362 (-5275 475);
PAINT SKYBLUE (-5275 475);
FORCEPROP 1 LAST PART_NUMBER CH4104K1B00
J 0
(-5275 325);
DISPLAY 0.489362 (-5275 325);
PAINT SKYBLUE (-5275 325);
FORCEPROP 1 LAST VALUE 0.1UF
J 0
(-5275 525);
DISPLAY 0.489362 (-5275 525);
PAINT SKYBLUE (-5275 525);
FORCEPROP 1 LAST TOLERANCE 10%
J 0
(-5275 425);
DISPLAY 0.489362 (-5275 425);
PAINT SKYBLUE (-5275 425);
FORCEPROP 1 LAST MATERIAL X7R
J 0
(-5275 375);
DISPLAY 0.489362 (-5275 375);
PAINT SKYBLUE (-5275 375);
FORCEPROP 1 LAST PATH I100
J 0
(-5275 625);
DISPLAY 0.978723 (-5275 625);
PAINT WHITE (-5275 625);
DISPLAY INVISIBLE (-5275 625);
FORCEPROP 2 LAST CDS_LIB pure_quanta
J 0
(-5325 475);
DISPLAY INVISIBLE (-5325 475);
FORCEPROP 2 LAST SEC_TYPE 0402
J 0
(-5275 675);
DISPLAY 1.021277 (-5275 675);
DISPLAY INVISIBLE (-5275 675);
FORCEADD Q_RES..1
(-5975 650);
FORCEPROP 1 LAST LOCATION PR388
J 0
(-6000 700);
DISPLAY 0.489362 (-6000 700);
PAINT SKYBLUE (-6000 700);
FORCEPROP 0 LAST $SEC 1
J 0
(-6025 750);
DISPLAY 0.680851 (-6025 750);
PAINT MONO (-6025 750);
DISPLAY INVISIBLE (-6025 750);
FORCEPROP 0 LAST CDS_SEC 1
J 0
(-6025 750);
DISPLAY 1.021277 (-6025 750);
DISPLAY INVISIBLE (-6025 750);
FORCEPROP 1 LASTPIN (-6075 650) $PN 1
J 0
(-6063 662);
DISPLAY 0.489362 (-6063 662);
PAINT MONO (-6063 662);
FORCEPROP 1 LASTPIN (-5875 650) $PN 2
J 0
(-5913 662);
DISPLAY 0.489362 (-5913 662);
PAINT MONO (-5913 662);
FORCEPROP 1 LAST PACK_TYPE 0402LF
J 0
(-5875 575);
DISPLAY 0.489362 (-5875 575);
PAINT SKYBLUE (-5875 575);
FORCEPROP 1 LAST VALUE 0
J 2
(-6100 675);
DISPLAY 0.489362 (-6100 675);
PAINT SKYBLUE (-6100 675);
FORCEPROP 1 LAST TOLERANCE 5%
J 0
(-5850 675);
DISPLAY 0.489362 (-5850 675);
PAINT SKYBLUE (-5850 675);
FORCEPROP 1 LAST MATERIAL CHIP
J 0
(-6225 575);
DISPLAY 0.489362 (-6225 575);
PAINT SKYBLUE (-6225 575);
FORCEPROP 1 LAST WATTAGE 1/16W
J 0
(-5875 600);
DISPLAY 0.489362 (-5875 600);
PAINT SKYBLUE (-5875 600);
FORCEPROP 1 LAST PART_NUMBER CS00002JB38
J 0
(-6225 600);
DISPLAY 0.489362 (-6225 600);
PAINT SKYBLUE (-6225 600);
FORCEPROP 1 LAST PATH I101
J 0
(-6025 800);
DISPLAY 0.978723 (-6025 800);
PAINT WHITE (-6025 800);
DISPLAY INVISIBLE (-6025 800);
FORCEPROP 2 LAST CDS_LIB pure_quanta
J 0
(-5975 650);
DISPLAY INVISIBLE (-5975 650);
FORCEADD UNIVERSAL_GND..1
(-5325 250);
FORCEPROP 3 LASTPIN (-5325 300) SIG_NAME GND\g
J 0
(-5315 310);
DISPLAY 0.659574 (-5315 310);
PAINT MONO (-5315 310);
DISPLAY INVISIBLE (-5315 310);
FORCEPROP 1 LAST HDL_POWER GND
J 1
(-5300 175);
DISPLAY 0.872340 (-5300 175);
PAINT GREEN (-5300 175);
DISPLAY INVISIBLE (-5300 175);
FORCEPROP 1 LAST PATH I102
J 0
(-5250 250);
DISPLAY 0.872340 (-5250 250);
PAINT AQUA (-5250 250);
DISPLAY INVISIBLE (-5250 250);
FORCEPROP 2 LAST CDS_LIB pure_quanta_power
J 0
(-5325 250);
DISPLAY INVISIBLE (-5325 250);
FORCEADD Q_RES..1
(-7200 825);
FORCEPROP 1 LAST LOCATION PR376
J 0
(-7250 875);
DISPLAY 0.489362 (-7250 875);
PAINT SKYBLUE (-7250 875);
FORCEPROP 0 LAST $SEC 1
J 0
(-7250 925);
DISPLAY 0.680851 (-7250 925);
PAINT MONO (-7250 925);
DISPLAY INVISIBLE (-7250 925);
FORCEPROP 0 LAST CDS_SEC 1
J 0
(-7250 925);
DISPLAY 1.021277 (-7250 925);
DISPLAY INVISIBLE (-7250 925);
FORCEPROP 1 LASTPIN (-7300 825) $PN 1
J 0
(-7288 837);
DISPLAY 0.489362 (-7288 837);
PAINT MONO (-7288 837);
FORCEPROP 1 LASTPIN (-7100 825) $PN 2
J 0
(-7138 837);
DISPLAY 0.489362 (-7138 837);
PAINT MONO (-7138 837);
FORCEPROP 1 LAST PACK_TYPE 0402LF
J 0
(-7075 750);
DISPLAY 0.489362 (-7075 750);
PAINT SKYBLUE (-7075 750);
FORCEPROP 1 LAST PART_NUMBER TMP_QCS34022FB15
J 0
(-7500 775);
DISPLAY 0.489362 (-7500 775);
PAINT SKYBLUE (-7500 775);
FORCEPROP 1 LAST VALUE 40.2K
J 2
(-7350 850);
DISPLAY 0.489362 (-7350 850);
PAINT SKYBLUE (-7350 850);
FORCEPROP 1 LAST TOLERANCE 1%
J 0
(-7050 850);
DISPLAY 0.489362 (-7050 850);
PAINT SKYBLUE (-7050 850);
FORCEPROP 1 LAST MATERIAL CHIP
J 0
(-7500 750);
DISPLAY 0.489362 (-7500 750);
PAINT SKYBLUE (-7500 750);
FORCEPROP 1 LAST WATTAGE 1/16W
J 0
(-7075 775);
DISPLAY 0.489362 (-7075 775);
PAINT SKYBLUE (-7075 775);
FORCEPROP 1 LAST PATH I104
J 0
(-7250 975);
DISPLAY 0.978723 (-7250 975);
PAINT WHITE (-7250 975);
DISPLAY INVISIBLE (-7250 975);
FORCEPROP 2 LAST CDS_LIB pure_quanta
J 0
(-7200 825);
DISPLAY INVISIBLE (-7200 825);
FORCEADD Q_RES..2
(-6450 650);
FORCEPROP 1 LAST LOCATION PR6
J 0
(-6400 750);
DISPLAY 0.489362 (-6400 750);
PAINT SKYBLUE (-6400 750);
FORCEPROP 2 LAST SEC 1
J 0
(-6400 875);
DISPLAY 0.680851 (-6400 875);
PAINT MONO (-6400 875);
DISPLAY INVISIBLE (-6400 875);
FORCEPROP 1 LASTPIN (-6450 750) $PN 1
J 0
(-6445 712);
DISPLAY 0.489362 (-6445 712);
PAINT MONO (-6445 712);
FORCEPROP 1 LASTPIN (-6450 550) $PN 2
J 0
(-6445 560);
DISPLAY 0.489362 (-6445 560);
PAINT MONO (-6445 560);
FORCEPROP 1 LAST PACK_TYPE 0402LF
J 0
(-6400 450);
DISPLAY 0.489362 (-6400 450);
PAINT SKYBLUE (-6400 450);
FORCEPROP 1 LAST VALUE 10K
J 0
(-6400 700);
DISPLAY 0.489362 (-6400 700);
PAINT SKYBLUE (-6400 700);
FORCEPROP 1 LAST TOLERANCE 1%
J 0
(-6400 650);
DISPLAY 0.489362 (-6400 650);
PAINT SKYBLUE (-6400 650);
FORCEPROP 1 LAST MATERIAL CHIP
J 0
(-6400 550);
DISPLAY 0.489362 (-6400 550);
PAINT SKYBLUE (-6400 550);
FORCEPROP 1 LAST WATTAGE 1/16W
J 0
(-6400 600);
DISPLAY 0.489362 (-6400 600);
PAINT SKYBLUE (-6400 600);
FORCEPROP 1 LAST PART_NUMBER TMP_QCS31002FB26
J 0
(-6400 500);
DISPLAY 0.489362 (-6400 500);
PAINT SKYBLUE (-6400 500);
FORCEPROP 1 LAST PATH I105
J 0
(-6400 825);
DISPLAY 0.978723 (-6400 825);
PAINT WHITE (-6400 825);
DISPLAY INVISIBLE (-6400 825);
FORCEPROP 2 LAST CDS_LIB pure_quanta
J 0
(-6450 650);
DISPLAY INVISIBLE (-6450 650);
FORCEPROP 2 LAST SEC_TYPE 0402LF
J 0
(-6400 875);
DISPLAY 1.021277 (-6400 875);
DISPLAY INVISIBLE (-6400 875);
FORCEADD UNIVERSAL_GND..1
(-6450 375);
FORCEPROP 3 LASTPIN (-6450 425) SIG_NAME GND\g
J 0
(-6440 435);
DISPLAY 0.659574 (-6440 435);
PAINT MONO (-6440 435);
DISPLAY INVISIBLE (-6440 435);
FORCEPROP 1 LAST HDL_POWER GND
J 1
(-6425 300);
DISPLAY 0.872340 (-6425 300);
PAINT GREEN (-6425 300);
DISPLAY INVISIBLE (-6425 300);
FORCEPROP 1 LAST PATH I107
J 0
(-6375 375);
DISPLAY 0.872340 (-6375 375);
PAINT AQUA (-6375 375);
DISPLAY INVISIBLE (-6375 375);
FORCEPROP 2 LAST CDS_LIB pure_quanta_power
J 0
(-6450 375);
DISPLAY INVISIBLE (-6450 375);
FORCEADD UNIVERSAL_GND..1
(-6875 400);
FORCEPROP 3 LASTPIN (-6875 450) SIG_NAME GND\g
J 0
(-6865 460);
DISPLAY 0.659574 (-6865 460);
PAINT MONO (-6865 460);
DISPLAY INVISIBLE (-6865 460);
FORCEPROP 1 LAST HDL_POWER GND
J 1
(-6850 325);
DISPLAY 0.872340 (-6850 325);
PAINT GREEN (-6850 325);
DISPLAY INVISIBLE (-6850 325);
FORCEPROP 1 LAST PATH I108
J 0
(-6800 400);
DISPLAY 0.872340 (-6800 400);
PAINT AQUA (-6800 400);
DISPLAY INVISIBLE (-6800 400);
FORCEPROP 2 LAST CDS_LIB pure_quanta_power
J 0
(-6875 400);
DISPLAY INVISIBLE (-6875 400);
FORCEADD VCC_CORE..1
(-7550 925);
FORCEPROP 3 LASTPIN (-7550 875) SIG_NAME P5V_STBY\g
J 0
(-7540 885);
DISPLAY 0.659574 (-7540 885);
PAINT MONO (-7540 885);
DISPLAY INVISIBLE (-7540 885);
FORCEPROP 1 LAST HDL_POWER P5V_STBY
J 1
(-7550 975);
DISPLAY 0.489362 (-7550 975);
PAINT GREEN (-7550 975);
FORCEPROP 1 LAST PATH I109
J 0
(-7500 950);
DISPLAY 0.872340 (-7500 950);
PAINT AQUA (-7500 950);
DISPLAY INVISIBLE (-7500 950);
FORCEPROP 2 LAST CDS_LIB pure_quanta_power
J 0
(-7550 925);
DISPLAY INVISIBLE (-7550 925);
FORCEADD Q_CAP..1
(-6875 650);
FORCEPROP 1 LAST LOCATION PC638
J 0
(-6800 750);
DISPLAY 0.489362 (-6800 750);
PAINT SKYBLUE (-6800 750);
FORCEPROP 0 LAST $SEC 1
J 0
(-6825 775);
DISPLAY 0.680851 (-6825 775);
PAINT MONO (-6825 775);
DISPLAY INVISIBLE (-6825 775);
FORCEPROP 0 LAST CDS_SEC 1
J 0
(-6825 775);
DISPLAY 1.021277 (-6825 775);
DISPLAY INVISIBLE (-6825 775);
FORCEPROP 1 LASTPIN (-6875 750) $PN 1
J 0
(-6865 730);
DISPLAY 0.489362 (-6865 730);
PAINT MONO (-6865 730);
FORCEPROP 1 LASTPIN (-6875 550) $PN 2
J 0
(-6865 530);
DISPLAY 0.489362 (-6865 530);
PAINT MONO (-6865 530);
FORCEPROP 1 LAST PACK_TYPE 0402
J 0
(-6800 450);
DISPLAY 0.489362 (-6800 450);
PAINT SKYBLUE (-6800 450);
FORCEPROP 1 LAST VOLTAGE 25V
J 0
(-6800 650);
DISPLAY 0.489362 (-6800 650);
PAINT SKYBLUE (-6800 650);
FORCEPROP 1 LAST PART_NUMBER CH4104K1B00
J 0
(-6800 500);
DISPLAY 0.489362 (-6800 500);
PAINT SKYBLUE (-6800 500);
FORCEPROP 1 LAST VALUE 0.1UF
J 0
(-6800 700);
DISPLAY 0.489362 (-6800 700);
PAINT SKYBLUE (-6800 700);
FORCEPROP 1 LAST TOLERANCE 10%
J 0
(-6800 600);
DISPLAY 0.489362 (-6800 600);
PAINT SKYBLUE (-6800 600);
FORCEPROP 1 LAST MATERIAL X7R
J 0
(-6800 550);
DISPLAY 0.489362 (-6800 550);
PAINT SKYBLUE (-6800 550);
FORCEPROP 1 LAST PATH I118
J 0
(-6825 800);
DISPLAY 0.978723 (-6825 800);
PAINT WHITE (-6825 800);
DISPLAY INVISIBLE (-6825 800);
FORCEPROP 2 LAST CDS_LIB pure_quanta
J 0
(-6875 650);
DISPLAY INVISIBLE (-6875 650);
FORCEADD UNIVERSAL_GND..1
(-2925 5425);
FORCEPROP 3 LASTPIN (-2925 5475) SIG_NAME GND\g
J 0
(-2915 5485);
DISPLAY 0.659574 (-2915 5485);
PAINT MONO (-2915 5485);
DISPLAY INVISIBLE (-2915 5485);
FORCEPROP 1 LAST HDL_POWER GND
J 1
(-2900 5350);
DISPLAY 0.872340 (-2900 5350);
PAINT GREEN (-2900 5350);
DISPLAY INVISIBLE (-2900 5350);
FORCEPROP 1 LAST PATH I12
J 0
(-2850 5425);
DISPLAY 0.872340 (-2850 5425);
PAINT AQUA (-2850 5425);
DISPLAY INVISIBLE (-2850 5425);
FORCEPROP 2 LAST CDS_LIB pure_quanta_power
J 0
(-2925 5425);
DISPLAY INVISIBLE (-2925 5425);
FORCEADD OFFPAGE..4
R 4
(-6725 5950);
FORCEPROP 2 LAST $XR0 80 
J 0
(-6946 5950);
DISPLAY 0.638298 (-6946 5950);
PAINT MONO (-6946 5950);
FORCEPROP 1 LAST COMMENT_BODY TRUE
R 2
J 0
(-6700 6050);
DISPLAY 0.872340 (-6700 6050);
PAINT GREEN (-6700 6050);
DISPLAY INVISIBLE (-6700 6050);
FORCEPROP 2 LAST CDS_LIB standard
R 2
J 2
(-6725 5950);
DISPLAY INVISIBLE (-6725 5950);
FORCEPROP 2 LAST PATH I127
R 2
J 2
(-6675 5875);
DISPLAY 1.021277 (-6675 5875);
DISPLAY INVISIBLE (-6675 5875);
FORCEPROP 1 LAST OFFPAGE TRUE
R 2
J 0
(-7050 6075);
DISPLAY 0.872340 (-7050 6075);
PAINT GREEN (-7050 6075);
DISPLAY INVISIBLE (-7050 6075);
FORCEADD Q_CAP..1
(-2925 5650);
FORCEPROP 1 LAST LOCATION PC644
J 0
(-2875 5750);
DISPLAY 0.489362 (-2875 5750);
PAINT SKYBLUE (-2875 5750);
FORCEPROP 0 LAST $SEC 1
J 0
(-2875 5775);
DISPLAY 0.680851 (-2875 5775);
PAINT MONO (-2875 5775);
DISPLAY INVISIBLE (-2875 5775);
FORCEPROP 0 LAST CDS_SEC 1
J 0
(-2875 5775);
DISPLAY 1.021277 (-2875 5775);
DISPLAY INVISIBLE (-2875 5775);
FORCEPROP 1 LASTPIN (-2925 5750) $PN 1
J 0
(-2915 5730);
DISPLAY 0.489362 (-2915 5730);
PAINT MONO (-2915 5730);
FORCEPROP 1 LASTPIN (-2925 5550) $PN 2
J 0
(-2915 5530);
DISPLAY 0.489362 (-2915 5530);
PAINT MONO (-2915 5530);
FORCEPROP 1 LAST PACK_TYPE C0402
J 0
(-2875 5450);
DISPLAY 0.489362 (-2875 5450);
PAINT SKYBLUE (-2875 5450);
FORCEPROP 1 LAST VOLTAGE 6.3V
J 0
(-2875 5650);
DISPLAY 0.489362 (-2875 5650);
PAINT SKYBLUE (-2875 5650);
FORCEPROP 1 LAST PART_NUMBER CH6101MEB01
J 0
(-2875 5500);
DISPLAY 0.489362 (-2875 5500);
PAINT SKYBLUE (-2875 5500);
FORCEPROP 1 LAST VALUE 10UF
J 0
(-2875 5700);
DISPLAY 0.489362 (-2875 5700);
PAINT SKYBLUE (-2875 5700);
FORCEPROP 1 LAST TOLERANCE 20%
J 0
(-2875 5600);
DISPLAY 0.489362 (-2875 5600);
PAINT SKYBLUE (-2875 5600);
FORCEPROP 1 LAST MATERIAL X6S
J 0
(-2875 5550);
DISPLAY 0.489362 (-2875 5550);
PAINT SKYBLUE (-2875 5550);
FORCEPROP 1 LAST PATH I13
J 0
(-2875 5800);
DISPLAY 0.978723 (-2875 5800);
PAINT WHITE (-2875 5800);
DISPLAY INVISIBLE (-2875 5800);
FORCEPROP 2 LAST CDS_LIB pure_quanta
J 0
(-2925 5650);
DISPLAY INVISIBLE (-2925 5650);
FORCEADD VCC_CORE..1
(-2125 6375);
FORCEPROP 3 LASTPIN (-2125 6325) SIG_NAME P3V3_STBY\g
J 0
(-2115 6335);
DISPLAY 0.659574 (-2115 6335);
PAINT MONO (-2115 6335);
DISPLAY INVISIBLE (-2115 6335);
FORCEPROP 1 LAST HDL_POWER P3V3_STBY
J 1
(-2125 6425);
DISPLAY 0.489362 (-2125 6425);
PAINT GREEN (-2125 6425);
FORCEPROP 1 LAST PATH I14
J 0
(-2075 6400);
DISPLAY 0.872340 (-2075 6400);
PAINT AQUA (-2075 6400);
DISPLAY INVISIBLE (-2075 6400);
FORCEPROP 2 LAST CDS_LIB pure_quanta_power
J 0
(-2125 6375);
DISPLAY INVISIBLE (-2125 6375);
FORCEADD UNIVERSAL_GND..1
R 2
(-5300 2550);
FORCEPROP 3 LASTPIN (-5300 2600) SIG_NAME GND\g
J 0
(-5290 2610);
DISPLAY 0.659574 (-5290 2610);
PAINT MONO (-5290 2610);
DISPLAY INVISIBLE (-5290 2610);
FORCEPROP 1 LAST HDL_POWER GND
J 1
(-5325 2475);
DISPLAY 0.872340 (-5325 2475);
PAINT GREEN (-5325 2475);
DISPLAY INVISIBLE (-5325 2475);
FORCEPROP 1 LAST PATH I146
J 2
(-5375 2550);
DISPLAY 0.872340 (-5375 2550);
PAINT AQUA (-5375 2550);
DISPLAY INVISIBLE (-5375 2550);
FORCEPROP 2 LAST CDS_LIB pure_quanta_power
J 0
(-5300 2550);
DISPLAY INVISIBLE (-5300 2550);
FORCEADD Q_RES..1
(-2500 6275);
FORCEPROP 1 LAST LOCATION PR393
J 0
(-2550 6325);
DISPLAY 0.489362 (-2550 6325);
PAINT SKYBLUE (-2550 6325);
FORCEPROP 0 LAST $SEC 1
J 0
(-2550 6375);
DISPLAY 0.680851 (-2550 6375);
PAINT MONO (-2550 6375);
DISPLAY INVISIBLE (-2550 6375);
FORCEPROP 0 LAST CDS_SEC 1
J 0
(-2550 6375);
DISPLAY 1.021277 (-2550 6375);
DISPLAY INVISIBLE (-2550 6375);
FORCEPROP 1 LASTPIN (-2600 6275) $PN 1
J 0
(-2588 6287);
DISPLAY 0.489362 (-2588 6287);
PAINT MONO (-2588 6287);
FORCEPROP 1 LASTPIN (-2400 6275) $PN 2
J 0
(-2438 6287);
DISPLAY 0.489362 (-2438 6287);
PAINT MONO (-2438 6287);
FORCEPROP 1 LAST PACK_TYPE 0402LF
J 0
(-2675 6200);
DISPLAY 0.489362 (-2675 6200);
PAINT SKYBLUE (-2675 6200);
FORCEPROP 1 LAST PART_NUMBER CS-1002FB23
J 0
(-2675 6225);
DISPLAY 0.489362 (-2675 6225);
PAINT SKYBLUE (-2675 6225);
FORCEPROP 1 LAST VALUE 1
J 2
(-2650 6300);
DISPLAY 0.489362 (-2650 6300);
PAINT SKYBLUE (-2650 6300);
FORCEPROP 1 LAST TOLERANCE 1%
J 0
(-2375 6300);
DISPLAY 0.489362 (-2375 6300);
PAINT SKYBLUE (-2375 6300);
FORCEPROP 1 LAST MATERIAL CHIP
J 0
(-2375 6225);
DISPLAY 0.489362 (-2375 6225);
PAINT SKYBLUE (-2375 6225);
FORCEPROP 1 LAST WATTAGE 1/16W
J 0
(-2375 6200);
DISPLAY 0.489362 (-2375 6200);
PAINT SKYBLUE (-2375 6200);
FORCEPROP 1 LAST PATH I148
J 0
(-2550 6425);
DISPLAY 0.978723 (-2550 6425);
PAINT WHITE (-2550 6425);
DISPLAY INVISIBLE (-2550 6425);
FORCEPROP 2 LAST CDS_LIB pure_quanta
J 0
(-2500 6275);
DISPLAY INVISIBLE (-2500 6275);
FORCEADD OFFPAGE..2
R 2
(-6725 6100);
FORCEPROP 2 LAST $XR0 80 
J 0
(-6979 6100);
DISPLAY 0.638298 (-6979 6100);
PAINT MONO (-6979 6100);
FORCEPROP 2 LAST PATH I149
J 0
(-6675 6175);
DISPLAY 1.021277 (-6675 6175);
DISPLAY INVISIBLE (-6675 6175);
FORCEPROP 2 LAST CDS_LIB standard
J 0
(-6725 6100);
DISPLAY INVISIBLE (-6725 6100);
FORCEPROP 1 LAST COMMENT_BODY TRUE
J 2
(-6680 6005);
DISPLAY 0.872340 (-6680 6005);
PAINT GREEN (-6680 6005);
DISPLAY INVISIBLE (-6680 6005);
FORCEPROP 1 LAST OFFPAGE TRUE
J 2
(-7050 5975);
DISPLAY 0.872340 (-7050 5975);
PAINT GREEN (-7050 5975);
DISPLAY INVISIBLE (-7050 5975);
FORCEADD OFFPAGE..5
R 2
(-2725 5800);
FORCEPROP 2 LAST $XR0 201 
J 0
(-2536 5800);
DISPLAY 0.638298 (-2536 5800);
PAINT MONO (-2536 5800);
FORCEPROP 2 LAST PATH I15
J 2
(-2775 5875);
DISPLAY 1.021277 (-2775 5875);
DISPLAY INVISIBLE (-2775 5875);
FORCEPROP 2 LAST CDS_LIB standard
J 2
(-2725 5800);
DISPLAY INVISIBLE (-2725 5800);
FORCEPROP 1 LAST COMMENT_BODY TRUE
J 2
(-2825 5725);
DISPLAY 0.872340 (-2825 5725);
PAINT GREEN (-2825 5725);
DISPLAY INVISIBLE (-2825 5725);
FORCEPROP 1 LAST OFFPAGE TRUE
J 2
(-3050 5675);
DISPLAY 0.872340 (-3050 5675);
PAINT GREEN (-3050 5675);
DISPLAY INVISIBLE (-3050 5675);
FORCEADD VCC_CORE..1
(-6525 6500);
FORCEPROP 3 LASTPIN (-6525 6450) SIG_NAME P3V3_STBY\g
J 0
(-6515 6460);
DISPLAY 0.659574 (-6515 6460);
PAINT MONO (-6515 6460);
DISPLAY INVISIBLE (-6515 6460);
FORCEPROP 1 LAST HDL_POWER P3V3_STBY
J 1
(-6525 6550);
DISPLAY 0.489362 (-6525 6550);
PAINT GREEN (-6525 6550);
FORCEPROP 1 LAST PATH I150
J 0
(-6475 6525);
DISPLAY 0.872340 (-6475 6525);
PAINT AQUA (-6475 6525);
DISPLAY INVISIBLE (-6475 6525);
FORCEPROP 2 LAST CDS_LIB pure_quanta_power
J 0
(-6525 6500);
DISPLAY INVISIBLE (-6525 6500);
FORCEADD Q_RES..1
(-6125 6375);
FORCEPROP 1 LAST LOCATION PR380
J 0
(-6175 6425);
DISPLAY 0.489362 (-6175 6425);
PAINT SKYBLUE (-6175 6425);
FORCEPROP 0 LAST $SEC 1
J 0
(-6175 6475);
DISPLAY 0.680851 (-6175 6475);
PAINT MONO (-6175 6475);
DISPLAY INVISIBLE (-6175 6475);
FORCEPROP 0 LAST CDS_SEC 1
J 0
(-6175 6475);
DISPLAY 1.021277 (-6175 6475);
DISPLAY INVISIBLE (-6175 6475);
FORCEPROP 1 LASTPIN (-6225 6375) $PN 1
J 0
(-6213 6387);
DISPLAY 0.489362 (-6213 6387);
PAINT MONO (-6213 6387);
FORCEPROP 1 LASTPIN (-6025 6375) $PN 2
J 0
(-6063 6387);
DISPLAY 0.489362 (-6063 6387);
PAINT MONO (-6063 6387);
FORCEPROP 1 LAST TOLERANCE 1%
J 0
(-6000 6400);
DISPLAY 0.489362 (-6000 6400);
PAINT SKYBLUE (-6000 6400);
FORCEPROP 1 LAST PACK_TYPE 0402LF
J 0
(-6025 6275);
DISPLAY 0.489362 (-6025 6275);
PAINT SKYBLUE (-6025 6275);
FORCEPROP 1 LAST PART_NUMBER TMP_QCS21002FB24
J 0
(-6450 6325);
DISPLAY 0.489362 (-6450 6325);
PAINT SKYBLUE (-6450 6325);
FORCEPROP 1 LAST VALUE 1K
J 2
(-6275 6400);
DISPLAY 0.489362 (-6275 6400);
PAINT SKYBLUE (-6275 6400);
FORCEPROP 1 LAST MATERIAL CHIP
J 0
(-6450 6275);
DISPLAY 0.489362 (-6450 6275);
PAINT SKYBLUE (-6450 6275);
FORCEPROP 1 LAST WATTAGE 1/16W
J 0
(-6025 6325);
DISPLAY 0.489362 (-6025 6325);
PAINT SKYBLUE (-6025 6325);
FORCEPROP 1 LAST PATH I151
J 0
(-6175 6525);
DISPLAY 0.978723 (-6175 6525);
PAINT WHITE (-6175 6525);
DISPLAY INVISIBLE (-6175 6525);
FORCEPROP 2 LAST CDS_LIB pure_quanta
J 0
(-6125 6375);
DISPLAY INVISIBLE (-6125 6375);
FORCEADD Q_RES..1
(-5900 6100);
FORCEPROP 1 LAST LOCATION PR385
J 0
(-5950 6150);
DISPLAY 0.489362 (-5950 6150);
PAINT SKYBLUE (-5950 6150);
FORCEPROP 0 LAST $SEC 1
J 0
(-5950 6200);
DISPLAY 0.680851 (-5950 6200);
PAINT MONO (-5950 6200);
DISPLAY INVISIBLE (-5950 6200);
FORCEPROP 0 LAST CDS_SEC 1
J 0
(-5950 6200);
DISPLAY 1.021277 (-5950 6200);
DISPLAY INVISIBLE (-5950 6200);
FORCEPROP 1 LASTPIN (-6000 6100) $PN 1
J 0
(-5988 6112);
DISPLAY 0.489362 (-5988 6112);
PAINT MONO (-5988 6112);
FORCEPROP 1 LASTPIN (-5800 6100) $PN 2
J 0
(-5838 6112);
DISPLAY 0.489362 (-5838 6112);
PAINT MONO (-5838 6112);
FORCEPROP 1 LAST PART_NUMBER CS00002JB38
J 0
(-6150 6050);
DISPLAY 0.489362 (-6150 6050);
PAINT SKYBLUE (-6150 6050);
FORCEPROP 1 LAST VALUE 0
J 2
(-6025 6125);
DISPLAY 0.489362 (-6025 6125);
PAINT SKYBLUE (-6025 6125);
FORCEPROP 1 LAST TOLERANCE 5%
J 0
(-5775 6125);
DISPLAY 0.489362 (-5775 6125);
PAINT SKYBLUE (-5775 6125);
FORCEPROP 1 LAST MATERIAL CHIP
J 0
(-6150 6025);
DISPLAY 0.489362 (-6150 6025);
PAINT SKYBLUE (-6150 6025);
FORCEPROP 1 LAST WATTAGE 1/16W
J 0
(-5800 6050);
DISPLAY 0.489362 (-5800 6050);
PAINT SKYBLUE (-5800 6050);
FORCEPROP 1 LAST PACK_TYPE 0402LF
J 0
(-5800 6025);
DISPLAY 0.489362 (-5800 6025);
PAINT SKYBLUE (-5800 6025);
FORCEPROP 1 LAST PATH I152
J 0
(-5950 6250);
DISPLAY 0.978723 (-5950 6250);
PAINT WHITE (-5950 6250);
DISPLAY INVISIBLE (-5950 6250);
FORCEPROP 2 LAST CDS_LIB pure_quanta
J 0
(-5900 6100);
DISPLAY INVISIBLE (-5900 6100);
FORCEADD Q_CAP..2
(-5250 6375);
FORCEPROP 1 LAST LOCATION PC641
J 1
(-5250 6450);
DISPLAY 0.489362 (-5250 6450);
PAINT SKYBLUE (-5250 6450);
FORCEPROP 0 LAST $SEC 1
J 0
(-5250 6525);
DISPLAY 0.680851 (-5250 6525);
PAINT MONO (-5250 6525);
DISPLAY INVISIBLE (-5250 6525);
FORCEPROP 0 LAST CDS_SEC 1
J 0
(-5250 6525);
DISPLAY 1.021277 (-5250 6525);
DISPLAY INVISIBLE (-5250 6525);
FORCEPROP 1 LASTPIN (-5350 6375) $PN 1
J 0
(-5360 6390);
DISPLAY 0.489362 (-5360 6390);
PAINT MONO (-5360 6390);
FORCEPROP 1 LASTPIN (-5150 6375) $PN 2
J 0
(-5165 6390);
DISPLAY 0.489362 (-5165 6390);
PAINT MONO (-5165 6390);
FORCEPROP 1 LAST PACK_TYPE 0402
J 0
(-5125 6300);
DISPLAY 0.489362 (-5125 6300);
PAINT SKYBLUE (-5125 6300);
FORCEPROP 1 LAST VOLTAGE 50V
J 0
(-5150 6425);
DISPLAY 0.489362 (-5150 6425);
PAINT SKYBLUE (-5150 6425);
FORCEPROP 1 LAST PART_NUMBER TMP_QCH21006JB10
J 1
(-5400 6300);
DISPLAY 0.489362 (-5400 6300);
PAINT SKYBLUE (-5400 6300);
FORCEPROP 1 LAST VALUE 1000PF
J 2
(-5375 6425);
DISPLAY 0.489362 (-5375 6425);
PAINT SKYBLUE (-5375 6425);
FORCEPROP 1 LAST TOLERANCE 5%
J 0
(-5125 6250);
DISPLAY 0.489362 (-5125 6250);
PAINT SKYBLUE (-5125 6250);
FORCEPROP 1 LAST MATERIAL EMPTY
J 0
(-5525 6250);
DISPLAY 0.489362 (-5525 6250);
PAINT RED (-5525 6250);
FORCEPROP 1 LAST PATH I153
J 0
(-5250 6575);
DISPLAY 0.978723 (-5250 6575);
PAINT WHITE (-5250 6575);
DISPLAY INVISIBLE (-5250 6575);
FORCEPROP 2 LAST CDS_LIB pure_quanta
J 0
(-5250 6375);
DISPLAY INVISIBLE (-5250 6375);
FORCEADD UNIVERSAL_GND..1
(-5000 6300);
FORCEPROP 3 LASTPIN (-5000 6350) SIG_NAME GND\g
J 0
(-4990 6360);
DISPLAY 0.659574 (-4990 6360);
PAINT MONO (-4990 6360);
DISPLAY INVISIBLE (-4990 6360);
FORCEPROP 1 LAST HDL_POWER GND
J 1
(-4975 6225);
DISPLAY 0.872340 (-4975 6225);
PAINT GREEN (-4975 6225);
DISPLAY INVISIBLE (-4975 6225);
FORCEPROP 1 LAST PATH I154
J 0
(-4925 6300);
DISPLAY 0.872340 (-4925 6300);
PAINT AQUA (-4925 6300);
DISPLAY INVISIBLE (-4925 6300);
FORCEPROP 2 LAST CDS_LIB pure_quanta_power
J 0
(-5000 6300);
DISPLAY INVISIBLE (-5000 6300);
FORCEADD OFFPAGE..4
(-3050 900);
FORCEPROP 2 LAST $XR0 201 
J 0
(-2864 900);
DISPLAY 0.638298 (-2864 900);
PAINT MONO (-2864 900);
FORCEPROP 1 LAST OFFPAGE TRUE
J 0
(-2725 775);
DISPLAY 0.872340 (-2725 775);
PAINT GREEN (-2725 775);
DISPLAY INVISIBLE (-2725 775);
FORCEPROP 2 LAST PATH I155
J 0
(-2875 975);
DISPLAY 1.021277 (-2875 975);
DISPLAY INVISIBLE (-2875 975);
FORCEPROP 2 LAST CDS_LIB standard
J 0
(-3050 900);
DISPLAY INVISIBLE (-3050 900);
FORCEPROP 1 LAST COMMENT_BODY TRUE
J 0
(-3075 800);
DISPLAY 0.872340 (-3075 800);
PAINT GREEN (-3075 800);
DISPLAY INVISIBLE (-3075 800);
FORCEADD UNIVERSAL_GND..1
(-3300 5425);
FORCEPROP 3 LASTPIN (-3300 5475) SIG_NAME GND\g
J 0
(-3290 5485);
DISPLAY 0.659574 (-3290 5485);
PAINT MONO (-3290 5485);
DISPLAY INVISIBLE (-3290 5485);
FORCEPROP 1 LAST HDL_POWER GND
J 1
(-3275 5350);
DISPLAY 0.872340 (-3275 5350);
PAINT GREEN (-3275 5350);
DISPLAY INVISIBLE (-3275 5350);
FORCEPROP 1 LAST PATH I159
J 0
(-3225 5425);
DISPLAY 0.872340 (-3225 5425);
PAINT AQUA (-3225 5425);
DISPLAY INVISIBLE (-3225 5425);
FORCEPROP 2 LAST CDS_LIB pure_quanta_power
J 0
(-3300 5425);
DISPLAY INVISIBLE (-3300 5425);
FORCEADD Q_CAP..1
(-3300 5650);
FORCEPROP 1 LAST LOCATION PC96
J 0
(-3250 5750);
DISPLAY 0.489362 (-3250 5750);
PAINT SKYBLUE (-3250 5750);
FORCEPROP 0 LAST $SEC 1
J 0
(-3250 5775);
DISPLAY 0.680851 (-3250 5775);
PAINT MONO (-3250 5775);
DISPLAY INVISIBLE (-3250 5775);
FORCEPROP 0 LAST CDS_SEC 1
J 0
(-3250 5775);
DISPLAY 1.021277 (-3250 5775);
DISPLAY INVISIBLE (-3250 5775);
FORCEPROP 1 LASTPIN (-3300 5750) $PN 1
J 0
(-3290 5730);
DISPLAY 0.489362 (-3290 5730);
PAINT MONO (-3290 5730);
FORCEPROP 1 LASTPIN (-3300 5550) $PN 2
J 0
(-3290 5530);
DISPLAY 0.489362 (-3290 5530);
PAINT MONO (-3290 5530);
FORCEPROP 1 LAST PACK_TYPE 0402
J 0
(-3250 5450);
DISPLAY 0.489362 (-3250 5450);
PAINT SKYBLUE (-3250 5450);
FORCEPROP 1 LAST VOLTAGE 25V
J 0
(-3250 5650);
DISPLAY 0.489362 (-3250 5650);
PAINT SKYBLUE (-3250 5650);
FORCEPROP 1 LAST VALUE 0.1UF
J 0
(-3250 5700);
DISPLAY 0.489362 (-3250 5700);
PAINT SKYBLUE (-3250 5700);
FORCEPROP 1 LAST TOLERANCE 10%
J 0
(-3250 5600);
DISPLAY 0.489362 (-3250 5600);
PAINT SKYBLUE (-3250 5600);
FORCEPROP 1 LAST MATERIAL X7R
J 0
(-3250 5550);
DISPLAY 0.489362 (-3250 5550);
PAINT SKYBLUE (-3250 5550);
FORCEPROP 1 LAST PART_NUMBER CH4104K1B00
J 0
(-3250 5500);
DISPLAY 0.489362 (-3250 5500);
PAINT SKYBLUE (-3250 5500);
FORCEPROP 1 LAST PATH I160
J 0
(-3250 5800);
DISPLAY 0.978723 (-3250 5800);
PAINT WHITE (-3250 5800);
DISPLAY INVISIBLE (-3250 5800);
FORCEPROP 2 LAST CDS_LIB pure_quanta
J 0
(-3300 5650);
DISPLAY INVISIBLE (-3300 5650);
FORCEADD UNIVERSAL_GND..1
(-3300 5875);
FORCEPROP 3 LASTPIN (-3300 5925) SIG_NAME GND\g
J 0
(-3290 5935);
DISPLAY 0.659574 (-3290 5935);
PAINT MONO (-3290 5935);
DISPLAY INVISIBLE (-3290 5935);
FORCEPROP 1 LAST HDL_POWER GND
J 1
(-3275 5800);
DISPLAY 0.872340 (-3275 5800);
PAINT GREEN (-3275 5800);
DISPLAY INVISIBLE (-3275 5800);
FORCEPROP 1 LAST PATH I161
J 0
(-3225 5875);
DISPLAY 0.872340 (-3225 5875);
PAINT AQUA (-3225 5875);
DISPLAY INVISIBLE (-3225 5875);
FORCEPROP 2 LAST CDS_LIB pure_quanta_power
J 0
(-3300 5875);
DISPLAY INVISIBLE (-3300 5875);
FORCEADD Q_CAP..1
(-3300 6125);
FORCEPROP 1 LAST LOCATION PC95
J 0
(-3250 6225);
DISPLAY 0.489362 (-3250 6225);
PAINT SKYBLUE (-3250 6225);
FORCEPROP 0 LAST $SEC 1
J 0
(-3250 6250);
DISPLAY 0.680851 (-3250 6250);
PAINT MONO (-3250 6250);
DISPLAY INVISIBLE (-3250 6250);
FORCEPROP 0 LAST CDS_SEC 1
J 0
(-3250 6250);
DISPLAY 1.021277 (-3250 6250);
DISPLAY INVISIBLE (-3250 6250);
FORCEPROP 1 LASTPIN (-3300 6225) $PN 1
J 0
(-3290 6205);
DISPLAY 0.489362 (-3290 6205);
PAINT MONO (-3290 6205);
FORCEPROP 1 LASTPIN (-3300 6025) $PN 2
J 0
(-3290 6005);
DISPLAY 0.489362 (-3290 6005);
PAINT MONO (-3290 6005);
FORCEPROP 1 LAST PACK_TYPE 0402
J 0
(-3250 5925);
DISPLAY 0.489362 (-3250 5925);
PAINT SKYBLUE (-3250 5925);
FORCEPROP 1 LAST VOLTAGE 25V
J 0
(-3250 6125);
DISPLAY 0.489362 (-3250 6125);
PAINT SKYBLUE (-3250 6125);
FORCEPROP 1 LAST PART_NUMBER CH4104K1B00
J 0
(-3250 5975);
DISPLAY 0.489362 (-3250 5975);
PAINT SKYBLUE (-3250 5975);
FORCEPROP 1 LAST VALUE 0.1UF
J 0
(-3250 6175);
DISPLAY 0.489362 (-3250 6175);
PAINT SKYBLUE (-3250 6175);
FORCEPROP 1 LAST TOLERANCE 10%
J 0
(-3250 6075);
DISPLAY 0.489362 (-3250 6075);
PAINT SKYBLUE (-3250 6075);
FORCEPROP 1 LAST MATERIAL X7R
J 0
(-3250 6025);
DISPLAY 0.489362 (-3250 6025);
PAINT SKYBLUE (-3250 6025);
FORCEPROP 1 LAST PATH I162
J 0
(-3250 6275);
DISPLAY 0.978723 (-3250 6275);
PAINT WHITE (-3250 6275);
DISPLAY INVISIBLE (-3250 6275);
FORCEPROP 2 LAST CDS_LIB pure_quanta
J 0
(-3300 6125);
DISPLAY INVISIBLE (-3300 6125);
FORCEADD UNIVERSAL_GND..1
(-2600 1125);
FORCEPROP 3 LASTPIN (-2600 1175) SIG_NAME GND\g
J 0
(-2590 1185);
DISPLAY 0.659574 (-2590 1185);
PAINT MONO (-2590 1185);
DISPLAY INVISIBLE (-2590 1185);
FORCEPROP 1 LAST HDL_POWER GND
J 1
(-2575 1050);
DISPLAY 0.872340 (-2575 1050);
PAINT GREEN (-2575 1050);
DISPLAY INVISIBLE (-2575 1050);
FORCEPROP 1 LAST PATH I164
J 0
(-2525 1125);
DISPLAY 0.872340 (-2525 1125);
PAINT AQUA (-2525 1125);
DISPLAY INVISIBLE (-2525 1125);
FORCEPROP 2 LAST CDS_LIB pure_quanta_power
J 0
(-2600 1125);
DISPLAY INVISIBLE (-2600 1125);
FORCEADD UNIVERSAL_GND..1
(-2050 1175);
FORCEPROP 3 LASTPIN (-2050 1225) SIG_NAME GND\g
J 0
(-2040 1235);
DISPLAY 0.659574 (-2040 1235);
PAINT MONO (-2040 1235);
DISPLAY INVISIBLE (-2040 1235);
FORCEPROP 1 LAST HDL_POWER GND
J 1
(-2025 1100);
DISPLAY 0.872340 (-2025 1100);
PAINT GREEN (-2025 1100);
DISPLAY INVISIBLE (-2025 1100);
FORCEPROP 1 LAST PATH I166
J 0
(-1975 1175);
DISPLAY 0.872340 (-1975 1175);
PAINT AQUA (-1975 1175);
DISPLAY INVISIBLE (-1975 1175);
FORCEPROP 2 LAST CDS_LIB pure_quanta_power
J 0
(-2050 1175);
DISPLAY INVISIBLE (-2050 1175);
FORCEADD Q_RES..2
(-2050 1400);
FORCEPROP 1 LAST LOCATION PR390
J 0
(-2005 1525);
DISPLAY 0.489362 (-2005 1525);
PAINT SKYBLUE (-2005 1525);
FORCEPROP 0 LAST $SEC 1
J 0
(-2000 1550);
DISPLAY 0.680851 (-2000 1550);
PAINT MONO (-2000 1550);
DISPLAY INVISIBLE (-2000 1550);
FORCEPROP 0 LAST CDS_SEC 1
J 0
(-2000 1550);
DISPLAY 1.021277 (-2000 1550);
DISPLAY INVISIBLE (-2000 1550);
FORCEPROP 1 LASTPIN (-2050 1500) $PN 1
J 0
(-2045 1462);
DISPLAY 0.489362 (-2045 1462);
PAINT MONO (-2045 1462);
FORCEPROP 1 LASTPIN (-2050 1300) $PN 2
J 0
(-2045 1310);
DISPLAY 0.489362 (-2045 1310);
PAINT MONO (-2045 1310);
FORCEPROP 1 LAST PACK_TYPE 0402LF
J 0
(-2010 1225);
DISPLAY 0.489362 (-2010 1225);
PAINT SKYBLUE (-2010 1225);
FORCEPROP 1 LAST PART_NUMBER CS00002JB38
J 0
(-2010 1275);
DISPLAY 0.489362 (-2010 1275);
PAINT SKYBLUE (-2010 1275);
FORCEPROP 1 LAST VALUE 0
J 0
(-2005 1475);
DISPLAY 0.489362 (-2005 1475);
PAINT SKYBLUE (-2005 1475);
FORCEPROP 1 LAST TOLERANCE 5%
J 0
(-2005 1425);
DISPLAY 0.489362 (-2005 1425);
PAINT SKYBLUE (-2005 1425);
FORCEPROP 1 LAST MATERIAL EMPTY
J 0
(-2010 1325);
DISPLAY 0.489362 (-2010 1325);
PAINT RED (-2010 1325);
FORCEPROP 1 LAST WATTAGE 1/16W
J 0
(-2010 1375);
DISPLAY 0.489362 (-2010 1375);
PAINT SKYBLUE (-2010 1375);
FORCEPROP 1 LAST PATH I167
J 0
(-2000 1575);
DISPLAY 0.978723 (-2000 1575);
PAINT WHITE (-2000 1575);
DISPLAY INVISIBLE (-2000 1575);
FORCEPROP 2 LAST CDS_LIB pure_quanta
J 0
(-2050 1400);
DISPLAY INVISIBLE (-2050 1400);
FORCEADD Q_RES..1
(-1575 1600);
FORCEPROP 1 LAST LOCATION PR392
J 0
(-1625 1650);
DISPLAY 0.489362 (-1625 1650);
PAINT SKYBLUE (-1625 1650);
FORCEPROP 0 LAST $SEC 1
J 0
(-1625 1675);
DISPLAY 0.680851 (-1625 1675);
PAINT MONO (-1625 1675);
DISPLAY INVISIBLE (-1625 1675);
FORCEPROP 0 LAST CDS_SEC 1
J 0
(-1625 1675);
DISPLAY 1.021277 (-1625 1675);
DISPLAY INVISIBLE (-1625 1675);
FORCEPROP 1 LASTPIN (-1675 1600) $PN 1
J 0
(-1663 1612);
DISPLAY 0.489362 (-1663 1612);
PAINT MONO (-1663 1612);
FORCEPROP 1 LASTPIN (-1475 1600) $PN 2
J 0
(-1513 1612);
DISPLAY 0.489362 (-1513 1612);
PAINT MONO (-1513 1612);
FORCEPROP 1 LAST PACK_TYPE 0402LF
J 0
(-1475 1525);
DISPLAY 0.489362 (-1475 1525);
PAINT SKYBLUE (-1475 1525);
FORCEPROP 1 LAST PART_NUMBER CS00002JB38
J 0
(-1825 1550);
DISPLAY 0.489362 (-1825 1550);
PAINT SKYBLUE (-1825 1550);
FORCEPROP 1 LAST VALUE 0
J 2
(-1700 1625);
DISPLAY 0.489362 (-1700 1625);
PAINT SKYBLUE (-1700 1625);
FORCEPROP 1 LAST TOLERANCE 5%
J 0
(-1450 1625);
DISPLAY 0.489362 (-1450 1625);
PAINT SKYBLUE (-1450 1625);
FORCEPROP 1 LAST MATERIAL EMPTY
J 0
(-1825 1525);
DISPLAY 0.489362 (-1825 1525);
PAINT RED (-1825 1525);
FORCEPROP 1 LAST WATTAGE 1/16W
J 0
(-1475 1550);
DISPLAY 0.489362 (-1475 1550);
PAINT SKYBLUE (-1475 1550);
FORCEPROP 1 LAST PATH I177
J 0
(-1625 1750);
DISPLAY 0.978723 (-1625 1750);
PAINT WHITE (-1625 1750);
DISPLAY INVISIBLE (-1625 1750);
FORCEPROP 2 LAST CDS_LIB pure_quanta
J 0
(-1575 1600);
DISPLAY INVISIBLE (-1575 1600);
FORCEADD Q_RES..1
(-1625 1825);
FORCEPROP 1 LAST LOCATION PR391
J 0
(-1675 1875);
DISPLAY 0.489362 (-1675 1875);
PAINT SKYBLUE (-1675 1875);
FORCEPROP 0 LAST $SEC 1
J 0
(-1675 1900);
DISPLAY 0.680851 (-1675 1900);
PAINT MONO (-1675 1900);
DISPLAY INVISIBLE (-1675 1900);
FORCEPROP 0 LAST CDS_SEC 1
J 0
(-1575 2000);
DISPLAY 1.021277 (-1575 2000);
DISPLAY INVISIBLE (-1575 2000);
FORCEPROP 1 LASTPIN (-1725 1825) $PN 1
J 0
(-1713 1837);
DISPLAY 0.489362 (-1713 1837);
PAINT MONO (-1713 1837);
FORCEPROP 1 LASTPIN (-1525 1825) $PN 2
J 0
(-1563 1837);
DISPLAY 0.489362 (-1563 1837);
PAINT MONO (-1563 1837);
FORCEPROP 1 LAST PACK_TYPE 0402LF
J 0
(-1450 1775);
DISPLAY 0.489362 (-1450 1775);
PAINT SKYBLUE (-1450 1775);
FORCEPROP 1 LAST PART_NUMBER TMP_QCS21002FB24
J 0
(-1850 1775);
DISPLAY 0.489362 (-1850 1775);
PAINT SKYBLUE (-1850 1775);
FORCEPROP 1 LAST VALUE 1K
J 2
(-1750 1850);
DISPLAY 0.489362 (-1750 1850);
PAINT SKYBLUE (-1750 1850);
FORCEPROP 1 LAST TOLERANCE 1%
J 0
(-1500 1850);
DISPLAY 0.489362 (-1500 1850);
PAINT SKYBLUE (-1500 1850);
FORCEPROP 1 LAST MATERIAL EMPTY
J 0
(-1850 1750);
DISPLAY 0.489362 (-1850 1750);
PAINT RED (-1850 1750);
FORCEPROP 1 LAST WATTAGE 1/16W
J 0
(-1450 1750);
DISPLAY 0.489362 (-1450 1750);
PAINT SKYBLUE (-1450 1750);
FORCEPROP 1 LAST PATH I178
J 0
(-1675 1975);
DISPLAY 0.978723 (-1675 1975);
PAINT WHITE (-1675 1975);
DISPLAY INVISIBLE (-1675 1975);
FORCEPROP 2 LAST CDS_LIB pure_quanta
J 0
(-1625 1825);
DISPLAY INVISIBLE (-1625 1825);
FORCEADD VCC_CORE..1
(-1275 1975);
FORCEPROP 3 LASTPIN (-1275 1925) SIG_NAME PVDD18_S5_P1\g
J 0
(-1265 1935);
DISPLAY 0.659574 (-1265 1935);
PAINT MONO (-1265 1935);
DISPLAY INVISIBLE (-1265 1935);
FORCEPROP 1 LAST HDL_POWER PVDD18_S5_P1
J 1
(-1275 2025);
DISPLAY 0.489362 (-1275 2025);
PAINT GREEN (-1275 2025);
FORCEPROP 1 LAST PATH I179
J 0
(-1225 2000);
DISPLAY 0.872340 (-1225 2000);
PAINT AQUA (-1225 2000);
DISPLAY INVISIBLE (-1225 2000);
FORCEPROP 2 LAST CDS_LIB pure_quanta_power
J 0
(-1275 1975);
DISPLAY INVISIBLE (-1275 1975);
FORCEADD OFFPAGE..4
(-675 1600);
FORCEPROP 2 LAST $XR0 80 
J 0
(-489 1600);
DISPLAY 0.638298 (-489 1600);
PAINT MONO (-489 1600);
FORCEPROP 2 LAST PATH I180
J 0
(-500 1675);
DISPLAY 1.021277 (-500 1675);
DISPLAY INVISIBLE (-500 1675);
FORCEPROP 1 LAST OFFPAGE TRUE
J 0
(-350 1475);
DISPLAY 0.872340 (-350 1475);
PAINT GREEN (-350 1475);
DISPLAY INVISIBLE (-350 1475);
FORCEPROP 2 LAST CDS_LIB standard
J 2
(-675 1600);
DISPLAY INVISIBLE (-675 1600);
FORCEPROP 1 LAST COMMENT_BODY TRUE
J 0
(-700 1500);
DISPLAY 0.872340 (-700 1500);
PAINT GREEN (-700 1500);
DISPLAY INVISIBLE (-700 1500);
FORCEADD Q_RES..1
(-3050 1200);
FORCEPROP 1 LAST LOCATION PR415
J 0
(-3100 1250);
DISPLAY 0.489362 (-3100 1250);
PAINT SKYBLUE (-3100 1250);
FORCEPROP 0 LAST $SEC 1
J 0
(-3100 1300);
DISPLAY 0.680851 (-3100 1300);
PAINT MONO (-3100 1300);
DISPLAY INVISIBLE (-3100 1300);
FORCEPROP 0 LAST CDS_SEC 1
J 0
(-3100 1300);
DISPLAY 1.021277 (-3100 1300);
DISPLAY INVISIBLE (-3100 1300);
FORCEPROP 1 LASTPIN (-3150 1200) $PN 1
J 0
(-3138 1212);
DISPLAY 0.489362 (-3138 1212);
PAINT MONO (-3138 1212);
FORCEPROP 1 LASTPIN (-2950 1200) $PN 2
J 0
(-2988 1212);
DISPLAY 0.489362 (-2988 1212);
PAINT MONO (-2988 1212);
FORCEPROP 1 LAST PACK_TYPE 0402LF
J 0
(-2950 1150);
DISPLAY 0.489362 (-2950 1150);
PAINT SKYBLUE (-2950 1150);
FORCEPROP 1 LAST PART_NUMBER CS00002JB38
J 0
(-3725 1150);
DISPLAY 0.489362 (-3725 1150);
PAINT SKYBLUE (-3725 1150);
FORCEPROP 1 LAST VALUE 0
J 2
(-3050 1150);
DISPLAY 0.489362 (-3050 1150);
PAINT SKYBLUE (-3050 1150);
FORCEPROP 1 LAST TOLERANCE 5%
J 0
(-3025 1150);
DISPLAY 0.489362 (-3025 1150);
PAINT SKYBLUE (-3025 1150);
FORCEPROP 1 LAST MATERIAL CHIP
J 0
(-3375 1150);
DISPLAY 0.489362 (-3375 1150);
PAINT SKYBLUE (-3375 1150);
FORCEPROP 1 LAST WATTAGE 1/16W
J 2
(-3125 1150);
DISPLAY 0.489362 (-3125 1150);
PAINT SKYBLUE (-3125 1150);
FORCEPROP 1 LAST PATH I182
J 0
(-3100 1350);
DISPLAY 0.978723 (-3100 1350);
PAINT WHITE (-3100 1350);
DISPLAY INVISIBLE (-3100 1350);
FORCEPROP 2 LAST CDS_LIB pure_quanta
J 0
(-3050 1200);
DISPLAY INVISIBLE (-3050 1200);
FORCEADD UNIVERSAL_GND..1
(-5975 5100);
FORCEPROP 3 LASTPIN (-5975 5150) SIG_NAME GND\g
J 0
(-5965 5160);
DISPLAY 0.659574 (-5965 5160);
PAINT MONO (-5965 5160);
DISPLAY INVISIBLE (-5965 5160);
FORCEPROP 1 LAST HDL_POWER GND
J 1
(-5950 5025);
DISPLAY 0.872340 (-5950 5025);
PAINT GREEN (-5950 5025);
DISPLAY INVISIBLE (-5950 5025);
FORCEPROP 1 LAST PATH I232
J 0
(-5900 5100);
DISPLAY 0.872340 (-5900 5100);
PAINT AQUA (-5900 5100);
DISPLAY INVISIBLE (-5900 5100);
FORCEPROP 2 LAST CDS_LIB pure_quanta_power
J 0
(-5975 5100);
DISPLAY INVISIBLE (-5975 5100);
FORCEADD VCC_CORE..1
(-6525 1825);
FORCEPROP 3 LASTPIN (-6525 1775) SIG_NAME P3V3_STBY\g
J 0
(-6515 1785);
DISPLAY 0.659574 (-6515 1785);
PAINT MONO (-6515 1785);
DISPLAY INVISIBLE (-6515 1785);
FORCEPROP 1 LAST HDL_POWER P3V3_STBY
J 1
(-6525 1875);
DISPLAY 0.489362 (-6525 1875);
PAINT GREEN (-6525 1875);
FORCEPROP 1 LAST PATH I237
J 0
(-6475 1850);
DISPLAY 0.872340 (-6475 1850);
PAINT AQUA (-6475 1850);
DISPLAY INVISIBLE (-6475 1850);
FORCEPROP 2 LAST CDS_LIB pure_quanta_power
J 0
(-6525 1825);
DISPLAY INVISIBLE (-6525 1825);
FORCEADD Q_RES..1
(-6100 1700);
FORCEPROP 1 LAST LOCATION PR146
J 0
(-6150 1750);
DISPLAY 0.489362 (-6150 1750);
PAINT SKYBLUE (-6150 1750);
FORCEPROP 0 LAST $SEC 1
J 0
(-6150 1775);
DISPLAY 0.680851 (-6150 1775);
PAINT MONO (-6150 1775);
DISPLAY INVISIBLE (-6150 1775);
FORCEPROP 0 LAST CDS_SEC 1
J 0
(-6150 1775);
DISPLAY 1.021277 (-6150 1775);
DISPLAY INVISIBLE (-6150 1775);
FORCEPROP 1 LASTPIN (-6200 1700) $PN 1
J 0
(-6188 1712);
DISPLAY 0.489362 (-6188 1712);
PAINT MONO (-6188 1712);
FORCEPROP 1 LASTPIN (-6000 1700) $PN 2
J 0
(-6038 1712);
DISPLAY 0.489362 (-6038 1712);
PAINT MONO (-6038 1712);
FORCEPROP 1 LAST PART_NUMBER CS00002JB38
J 0
(-6350 1650);
DISPLAY 0.489362 (-6350 1650);
PAINT SKYBLUE (-6350 1650);
FORCEPROP 1 LAST VALUE 0
J 2
(-6225 1725);
DISPLAY 0.489362 (-6225 1725);
PAINT SKYBLUE (-6225 1725);
FORCEPROP 1 LAST TOLERANCE 5%
J 0
(-5975 1725);
DISPLAY 0.489362 (-5975 1725);
PAINT SKYBLUE (-5975 1725);
FORCEPROP 1 LAST MATERIAL EMPTY
J 0
(-6350 1625);
DISPLAY 0.489362 (-6350 1625);
PAINT RED (-6350 1625);
FORCEPROP 1 LAST WATTAGE 1/16W
J 0
(-6000 1650);
DISPLAY 0.489362 (-6000 1650);
PAINT SKYBLUE (-6000 1650);
FORCEPROP 1 LAST PACK_TYPE 0402LF
J 0
(-6000 1625);
DISPLAY 0.489362 (-6000 1625);
PAINT SKYBLUE (-6000 1625);
FORCEPROP 1 LAST PATH I238
J 0
(-6150 1850);
DISPLAY 0.978723 (-6150 1850);
PAINT WHITE (-6150 1850);
DISPLAY INVISIBLE (-6150 1850);
FORCEPROP 2 LAST CDS_LIB pure_quanta
J 0
(-6100 1700);
DISPLAY INVISIBLE (-6100 1700);
FORCEADD OFFPAGE..2
R 2
(-6925 2100);
FORCEPROP 2 LAST $XR0 81 
J 0
(-7179 2100);
DISPLAY 0.638298 (-7179 2100);
PAINT MONO (-7179 2100);
FORCEPROP 2 LAST PATH I239
J 0
(-6875 2175);
DISPLAY 1.021277 (-6875 2175);
DISPLAY INVISIBLE (-6875 2175);
FORCEPROP 2 LAST CDS_LIB standard
J 0
(-6925 2100);
DISPLAY INVISIBLE (-6925 2100);
FORCEPROP 1 LAST COMMENT_BODY TRUE
J 2
(-6880 2005);
DISPLAY 0.872340 (-6880 2005);
PAINT GREEN (-6880 2005);
DISPLAY INVISIBLE (-6880 2005);
FORCEPROP 1 LAST OFFPAGE TRUE
J 2
(-7250 1975);
DISPLAY 0.872340 (-7250 1975);
PAINT GREEN (-7250 1975);
DISPLAY INVISIBLE (-7250 1975);
FORCEADD Q_RES..1
(-6175 2100);
FORCEPROP 1 LAST LOCATION PR10
J 0
(-6225 2150);
DISPLAY 0.489362 (-6225 2150);
PAINT SKYBLUE (-6225 2150);
FORCEPROP 0 LAST $SEC 1
J 0
(-6225 2200);
DISPLAY 0.680851 (-6225 2200);
PAINT MONO (-6225 2200);
DISPLAY INVISIBLE (-6225 2200);
FORCEPROP 0 LAST CDS_SEC 1
J 0
(-6225 2200);
DISPLAY 1.021277 (-6225 2200);
DISPLAY INVISIBLE (-6225 2200);
FORCEPROP 1 LASTPIN (-6275 2100) $PN 1
J 0
(-6263 2112);
DISPLAY 0.489362 (-6263 2112);
PAINT MONO (-6263 2112);
FORCEPROP 1 LASTPIN (-6075 2100) $PN 2
J 0
(-6113 2112);
DISPLAY 0.489362 (-6113 2112);
PAINT MONO (-6113 2112);
FORCEPROP 1 LAST PACK_TYPE 0402LF
J 0
(-6075 2025);
DISPLAY 0.489362 (-6075 2025);
PAINT SKYBLUE (-6075 2025);
FORCEPROP 1 LAST PART_NUMBER CS00002JB38
J 0
(-6425 2050);
DISPLAY 0.489362 (-6425 2050);
PAINT SKYBLUE (-6425 2050);
FORCEPROP 1 LAST VALUE 0
J 2
(-6300 2125);
DISPLAY 0.489362 (-6300 2125);
PAINT SKYBLUE (-6300 2125);
FORCEPROP 1 LAST MATERIAL EMPTY
J 0
(-6425 2025);
DISPLAY 0.489362 (-6425 2025);
PAINT RED (-6425 2025);
FORCEPROP 1 LAST TOLERANCE 5%
J 0
(-6050 2125);
DISPLAY 0.489362 (-6050 2125);
PAINT SKYBLUE (-6050 2125);
FORCEPROP 1 LAST WATTAGE 1/16W
J 0
(-6075 2050);
DISPLAY 0.489362 (-6075 2050);
PAINT SKYBLUE (-6075 2050);
FORCEPROP 1 LAST PATH I240
J 0
(-6225 2250);
DISPLAY 0.978723 (-6225 2250);
PAINT WHITE (-6225 2250);
DISPLAY INVISIBLE (-6225 2250);
FORCEPROP 2 LAST CDS_LIB pure_quanta
J 0
(-6175 2100);
DISPLAY INVISIBLE (-6175 2100);
FORCEADD Q_RES..2
(-5900 2325);
FORCEPROP 1 LAST LOCATION PR11
J 0
(-5855 2450);
DISPLAY 0.489362 (-5855 2450);
PAINT SKYBLUE (-5855 2450);
FORCEPROP 0 LAST $SEC 1
J 0
(-5850 2500);
DISPLAY 0.680851 (-5850 2500);
PAINT MONO (-5850 2500);
DISPLAY INVISIBLE (-5850 2500);
FORCEPROP 0 LAST CDS_SEC 1
J 0
(-5850 2500);
DISPLAY 1.021277 (-5850 2500);
DISPLAY INVISIBLE (-5850 2500);
FORCEPROP 1 LASTPIN (-5900 2425) $PN 1
J 0
(-5895 2387);
DISPLAY 0.489362 (-5895 2387);
PAINT MONO (-5895 2387);
FORCEPROP 1 LASTPIN (-5900 2225) $PN 2
J 0
(-5895 2235);
DISPLAY 0.489362 (-5895 2235);
PAINT MONO (-5895 2235);
FORCEPROP 1 LAST PACK_TYPE 0402LF
J 0
(-5860 2150);
DISPLAY 0.489362 (-5860 2150);
PAINT SKYBLUE (-5860 2150);
FORCEPROP 1 LAST PART_NUMBER TMP_QCS21002FB24
J 0
(-5860 2200);
DISPLAY 0.489362 (-5860 2200);
PAINT SKYBLUE (-5860 2200);
FORCEPROP 1 LAST VALUE 1K
J 0
(-5855 2400);
DISPLAY 0.489362 (-5855 2400);
PAINT SKYBLUE (-5855 2400);
FORCEPROP 1 LAST TOLERANCE 1%
J 0
(-5855 2350);
DISPLAY 0.489362 (-5855 2350);
PAINT SKYBLUE (-5855 2350);
FORCEPROP 1 LAST MATERIAL EMPTY
J 0
(-5860 2250);
DISPLAY 0.489362 (-5860 2250);
PAINT RED (-5860 2250);
FORCEPROP 1 LAST WATTAGE 1/16W
J 0
(-5860 2300);
DISPLAY 0.489362 (-5860 2300);
PAINT SKYBLUE (-5860 2300);
FORCEPROP 1 LAST PATH I241
J 0
(-5850 2500);
DISPLAY 0.978723 (-5850 2500);
PAINT WHITE (-5850 2500);
DISPLAY INVISIBLE (-5850 2500);
FORCEPROP 2 LAST CDS_LIB pure_quanta
J 0
(-5900 2325);
DISPLAY INVISIBLE (-5900 2325);
FORCEADD VCC_CORE..1
(-5900 2525);
FORCEPROP 3 LASTPIN (-5900 2475) SIG_NAME PVDD18_S5_P0\g
J 0
(-5890 2485);
DISPLAY 0.659574 (-5890 2485);
PAINT MONO (-5890 2485);
DISPLAY INVISIBLE (-5890 2485);
FORCEPROP 1 LAST HDL_POWER PVDD18_S5_P0
J 1
(-5900 2575);
DISPLAY 0.489362 (-5900 2575);
PAINT GREEN (-5900 2575);
FORCEPROP 1 LAST PATH I242
J 0
(-5850 2550);
DISPLAY 0.872340 (-5850 2550);
PAINT AQUA (-5850 2550);
DISPLAY INVISIBLE (-5850 2550);
FORCEPROP 2 LAST CDS_LIB pure_quanta_power
J 0
(-5900 2525);
DISPLAY INVISIBLE (-5900 2525);
FORCEADD Q_RES..2
(-6675 4225);
FORCEPROP 1 LAST LOCATION PR229
J 0
(-6630 4350);
DISPLAY 0.489362 (-6630 4350);
PAINT SKYBLUE (-6630 4350);
FORCEPROP 0 LAST $SEC 1
J 0
(-6625 4400);
DISPLAY 0.680851 (-6625 4400);
PAINT MONO (-6625 4400);
DISPLAY INVISIBLE (-6625 4400);
FORCEPROP 0 LAST CDS_SEC 1
J 0
(-6625 4400);
DISPLAY 1.021277 (-6625 4400);
DISPLAY INVISIBLE (-6625 4400);
FORCEPROP 1 LASTPIN (-6675 4325) $PN 1
J 0
(-6670 4287);
DISPLAY 0.489362 (-6670 4287);
PAINT MONO (-6670 4287);
FORCEPROP 1 LASTPIN (-6675 4125) $PN 2
J 0
(-6670 4135);
DISPLAY 0.489362 (-6670 4135);
PAINT MONO (-6670 4135);
FORCEPROP 1 LAST PACK_TYPE 0402LF
J 0
(-6625 4050);
DISPLAY 0.489362 (-6625 4050);
PAINT SKYBLUE (-6625 4050);
FORCEPROP 1 LAST PART_NUMBER CS04992FB31
J 0
(-6625 4100);
DISPLAY 0.489362 (-6625 4100);
PAINT SKYBLUE (-6625 4100);
FORCEPROP 1 LAST MATERIAL CHIP
J 0
(-6625 4150);
DISPLAY 0.489362 (-6625 4150);
PAINT SKYBLUE (-6625 4150);
FORCEPROP 1 LAST WATTAGE 1/16W
J 0
(-6625 4200);
DISPLAY 0.489362 (-6625 4200);
PAINT SKYBLUE (-6625 4200);
FORCEPROP 1 LAST VALUE 49.9
J 0
(-6625 4300);
DISPLAY 0.489362 (-6625 4300);
PAINT SKYBLUE (-6625 4300);
FORCEPROP 1 LAST TOLERANCE 1%
J 0
(-6625 4250);
DISPLAY 0.489362 (-6625 4250);
PAINT SKYBLUE (-6625 4250);
FORCEPROP 1 LAST PATH I243
J 0
(-6625 4400);
DISPLAY 0.978723 (-6625 4400);
PAINT WHITE (-6625 4400);
DISPLAY INVISIBLE (-6625 4400);
FORCEPROP 2 LAST CDS_LIB pure_quanta
J 0
(-6675 4225);
DISPLAY INVISIBLE (-6675 4225);
FORCEADD VCC_CORE..1
(-6675 4425);
FORCEPROP 3 LASTPIN (-6675 4375) SIG_NAME PVDD11_S3_P1\g
J 0
(-6665 4385);
DISPLAY 0.659574 (-6665 4385);
PAINT MONO (-6665 4385);
DISPLAY INVISIBLE (-6665 4385);
FORCEPROP 1 LAST HDL_POWER PVDD11_S3_P1
J 1
(-6675 4475);
DISPLAY 0.489362 (-6675 4475);
PAINT GREEN (-6675 4475);
FORCEPROP 1 LAST PATH I244
J 0
(-6625 4450);
DISPLAY 0.872340 (-6625 4450);
PAINT AQUA (-6625 4450);
DISPLAY INVISIBLE (-6625 4450);
FORCEPROP 2 LAST CDS_LIB pure_quanta_power
J 0
(-6675 4425);
DISPLAY INVISIBLE (-6675 4425);
FORCEADD Q_RES..2
(-6675 3650);
FORCEPROP 1 LAST LOCATION PR288
J 0
(-6630 3775);
DISPLAY 0.489362 (-6630 3775);
PAINT SKYBLUE (-6630 3775);
FORCEPROP 0 LAST $SEC 1
J 0
(-6625 3825);
DISPLAY 0.680851 (-6625 3825);
PAINT MONO (-6625 3825);
DISPLAY INVISIBLE (-6625 3825);
FORCEPROP 0 LAST CDS_SEC 1
J 0
(-6625 3825);
DISPLAY 1.021277 (-6625 3825);
DISPLAY INVISIBLE (-6625 3825);
FORCEPROP 1 LASTPIN (-6675 3750) $PN 1
J 0
(-6670 3712);
DISPLAY 0.489362 (-6670 3712);
PAINT MONO (-6670 3712);
FORCEPROP 1 LASTPIN (-6675 3550) $PN 2
J 0
(-6670 3560);
DISPLAY 0.489362 (-6670 3560);
PAINT MONO (-6670 3560);
FORCEPROP 1 LAST PACK_TYPE 0402LF
J 0
(-6625 3475);
DISPLAY 0.489362 (-6625 3475);
PAINT SKYBLUE (-6625 3475);
FORCEPROP 1 LAST PART_NUMBER CS04992FB31
J 0
(-6625 3525);
DISPLAY 0.489362 (-6625 3525);
PAINT SKYBLUE (-6625 3525);
FORCEPROP 1 LAST MATERIAL CHIP
J 0
(-6625 3575);
DISPLAY 0.489362 (-6625 3575);
PAINT SKYBLUE (-6625 3575);
FORCEPROP 1 LAST WATTAGE 1/16W
J 0
(-6625 3625);
DISPLAY 0.489362 (-6625 3625);
PAINT SKYBLUE (-6625 3625);
FORCEPROP 1 LAST VALUE 49.9
J 0
(-6625 3725);
DISPLAY 0.489362 (-6625 3725);
PAINT SKYBLUE (-6625 3725);
FORCEPROP 1 LAST TOLERANCE 1%
J 0
(-6625 3675);
DISPLAY 0.489362 (-6625 3675);
PAINT SKYBLUE (-6625 3675);
FORCEPROP 1 LAST PATH I245
J 0
(-6625 3825);
DISPLAY 0.978723 (-6625 3825);
PAINT WHITE (-6625 3825);
DISPLAY INVISIBLE (-6625 3825);
FORCEPROP 2 LAST CDS_LIB pure_quanta
J 0
(-6675 3650);
DISPLAY INVISIBLE (-6675 3650);
FORCEADD UNIVERSAL_GND..1
(-6675 3475);
FORCEPROP 3 LASTPIN (-6675 3525) SIG_NAME GND\g
J 0
(-6665 3535);
DISPLAY 0.659574 (-6665 3535);
PAINT MONO (-6665 3535);
DISPLAY INVISIBLE (-6665 3535);
FORCEPROP 1 LAST HDL_POWER GND
J 1
(-6650 3400);
DISPLAY 0.872340 (-6650 3400);
PAINT GREEN (-6650 3400);
DISPLAY INVISIBLE (-6650 3400);
FORCEPROP 1 LAST PATH I246
J 0
(-6600 3475);
DISPLAY 0.872340 (-6600 3475);
PAINT AQUA (-6600 3475);
DISPLAY INVISIBLE (-6600 3475);
FORCEPROP 2 LAST CDS_LIB pure_quanta_power
J 0
(-6675 3475);
DISPLAY INVISIBLE (-6675 3475);
FORCEADD Q_RES..1
(-5825 1400);
FORCEPROP 1 LAST LOCATION PR464
J 0
(-5825 1425);
DISPLAY 0.489362 (-5825 1425);
PAINT SKYBLUE (-5825 1425);
FORCEPROP 0 LAST $SEC 1
J 0
(-5700 1450);
DISPLAY 0.680851 (-5700 1450);
PAINT MONO (-5700 1450);
DISPLAY INVISIBLE (-5700 1450);
FORCEPROP 0 LAST CDS_SEC 1
J 0
(-5700 1450);
DISPLAY 1.021277 (-5700 1450);
DISPLAY INVISIBLE (-5700 1450);
FORCEPROP 1 LASTPIN (-5925 1400) $PN 1
J 0
(-5913 1412);
DISPLAY 0.787234 (-5913 1412);
PAINT MONO (-5913 1412);
DISPLAY INVISIBLE (-5913 1412);
FORCEPROP 1 LASTPIN (-5725 1400) $PN 2
J 0
(-5763 1412);
DISPLAY 0.787234 (-5763 1412);
PAINT MONO (-5763 1412);
DISPLAY INVISIBLE (-5763 1412);
FORCEPROP 1 LAST PACK_TYPE 0402LF
J 0
(-5725 1325);
DISPLAY 0.489362 (-5725 1325);
PAINT SKYBLUE (-5725 1325);
FORCEPROP 1 LAST TOLERANCE 1%  
J 0
(-5700 1425);
DISPLAY 0.489362 (-5700 1425);
PAINT SKYBLUE (-5700 1425);
FORCEPROP 1 LAST MATERIAL CHIP
J 0
(-6075 1325);
DISPLAY 0.489362 (-6075 1325);
PAINT SKYBLUE (-6075 1325);
FORCEPROP 1 LAST WATTAGE 1/16W
J 0
(-5725 1350);
DISPLAY 0.489362 (-5725 1350);
PAINT SKYBLUE (-5725 1350);
FORCEPROP 1 LAST VALUE 13.7K    
J 2
(-5825 1425);
DISPLAY 0.489362 (-5825 1425);
PAINT SKYBLUE (-5825 1425);
FORCEPROP 1 LAST PART_NUMBER CS31372FB11
J 0
(-6075 1350);
DISPLAY 0.489362 (-6075 1350);
PAINT SKYBLUE (-6075 1350);
FORCEPROP 1 LAST PATH I247
J 0
(-5875 1550);
DISPLAY 0.978723 (-5875 1550);
PAINT WHITE (-5875 1550);
DISPLAY INVISIBLE (-5875 1550);
FORCEPROP 2 LAST CDS_LIB pure_quanta
J 0
(-5825 1400);
DISPLAY INVISIBLE (-5825 1400);
FORCEADD UNIVERSAL_GND..1
(-6100 1125);
FORCEPROP 3 LASTPIN (-6100 1175) SIG_NAME GND\g
J 0
(-6090 1185);
DISPLAY 0.659574 (-6090 1185);
PAINT MONO (-6090 1185);
DISPLAY INVISIBLE (-6090 1185);
FORCEPROP 1 LAST HDL_POWER GND
J 1
(-6075 1050);
DISPLAY 0.872340 (-6075 1050);
PAINT GREEN (-6075 1050);
DISPLAY INVISIBLE (-6075 1050);
FORCEPROP 1 LAST PATH I248
J 0
(-6025 1125);
DISPLAY 0.872340 (-6025 1125);
PAINT AQUA (-6025 1125);
DISPLAY INVISIBLE (-6025 1125);
FORCEPROP 2 LAST CDS_LIB pure_quanta_power
J 0
(-6100 1125);
DISPLAY INVISIBLE (-6100 1125);
FORCEADD UNIVERSAL_GND..1
(-2600 4025);
FORCEPROP 3 LASTPIN (-2600 4075) SIG_NAME GND\g
J 0
(-2590 4085);
DISPLAY 0.659574 (-2590 4085);
PAINT MONO (-2590 4085);
DISPLAY INVISIBLE (-2590 4085);
FORCEPROP 1 LAST HDL_POWER GND
J 1
(-2575 3950);
DISPLAY 0.872340 (-2575 3950);
PAINT GREEN (-2575 3950);
DISPLAY INVISIBLE (-2575 3950);
FORCEPROP 1 LAST PATH I269
J 0
(-2525 4025);
DISPLAY 0.872340 (-2525 4025);
PAINT AQUA (-2525 4025);
DISPLAY INVISIBLE (-2525 4025);
FORCEPROP 2 LAST CDS_LIB pure_quanta_power
J 0
(-2600 4025);
DISPLAY INVISIBLE (-2600 4025);
FORCEADD UNIVERSAL_GND..1
(-2600 3575);
FORCEPROP 3 LASTPIN (-2600 3625) SIG_NAME GND\g
J 0
(-2590 3635);
DISPLAY 0.659574 (-2590 3635);
PAINT MONO (-2590 3635);
DISPLAY INVISIBLE (-2590 3635);
FORCEPROP 1 LAST HDL_POWER GND
J 1
(-2575 3500);
DISPLAY 0.872340 (-2575 3500);
PAINT GREEN (-2575 3500);
DISPLAY INVISIBLE (-2575 3500);
FORCEPROP 1 LAST PATH I270
J 0
(-2525 3575);
DISPLAY 0.872340 (-2525 3575);
PAINT AQUA (-2525 3575);
DISPLAY INVISIBLE (-2525 3575);
FORCEPROP 2 LAST CDS_LIB pure_quanta_power
J 0
(-2600 3575);
DISPLAY INVISIBLE (-2600 3575);
FORCEADD Q_RES..1
(-3050 4100);
FORCEPROP 1 LAST LOCATION PR406
J 0
(-3100 4150);
DISPLAY 0.489362 (-3100 4150);
PAINT SKYBLUE (-3100 4150);
FORCEPROP 0 LAST $SEC 1
J 0
(-3100 4200);
DISPLAY 0.680851 (-3100 4200);
PAINT MONO (-3100 4200);
DISPLAY INVISIBLE (-3100 4200);
FORCEPROP 0 LAST CDS_SEC 1
J 0
(-3100 4200);
DISPLAY 1.021277 (-3100 4200);
DISPLAY INVISIBLE (-3100 4200);
FORCEPROP 1 LASTPIN (-3150 4100) $PN 1
J 0
(-3138 4112);
DISPLAY 0.489362 (-3138 4112);
PAINT MONO (-3138 4112);
FORCEPROP 1 LASTPIN (-2950 4100) $PN 2
J 0
(-2988 4112);
DISPLAY 0.489362 (-2988 4112);
PAINT MONO (-2988 4112);
FORCEPROP 1 LAST PACK_TYPE 0402LF
J 0
(-2950 4050);
DISPLAY 0.489362 (-2950 4050);
PAINT SKYBLUE (-2950 4050);
FORCEPROP 1 LAST PART_NUMBER CS00002JB38
J 0
(-3725 4050);
DISPLAY 0.489362 (-3725 4050);
PAINT SKYBLUE (-3725 4050);
FORCEPROP 1 LAST VALUE 0
J 2
(-3050 4050);
DISPLAY 0.489362 (-3050 4050);
PAINT SKYBLUE (-3050 4050);
FORCEPROP 1 LAST TOLERANCE 5%
J 0
(-3025 4050);
DISPLAY 0.489362 (-3025 4050);
PAINT SKYBLUE (-3025 4050);
FORCEPROP 1 LAST WATTAGE 1/16W
J 2
(-3125 4050);
DISPLAY 0.489362 (-3125 4050);
PAINT SKYBLUE (-3125 4050);
FORCEPROP 1 LAST MATERIAL CHIP
J 0
(-3375 4050);
DISPLAY 0.489362 (-3375 4050);
PAINT SKYBLUE (-3375 4050);
FORCEPROP 1 LAST PATH I271
J 0
(-3100 4250);
DISPLAY 0.978723 (-3100 4250);
PAINT WHITE (-3100 4250);
DISPLAY INVISIBLE (-3100 4250);
FORCEPROP 2 LAST CDS_LIB pure_quanta
J 0
(-3050 4100);
DISPLAY INVISIBLE (-3050 4100);
FORCEADD Q_RES..1
(-3050 3650);
FORCEPROP 1 LAST LOCATION PR407
J 0
(-3100 3700);
DISPLAY 0.489362 (-3100 3700);
PAINT SKYBLUE (-3100 3700);
FORCEPROP 0 LAST $SEC 1
J 0
(-3100 3750);
DISPLAY 0.680851 (-3100 3750);
PAINT MONO (-3100 3750);
DISPLAY INVISIBLE (-3100 3750);
FORCEPROP 0 LAST CDS_SEC 1
J 0
(-3100 3750);
DISPLAY 1.021277 (-3100 3750);
DISPLAY INVISIBLE (-3100 3750);
FORCEPROP 1 LASTPIN (-3150 3650) $PN 1
J 0
(-3138 3662);
DISPLAY 0.489362 (-3138 3662);
PAINT MONO (-3138 3662);
FORCEPROP 1 LASTPIN (-2950 3650) $PN 2
J 0
(-2988 3662);
DISPLAY 0.489362 (-2988 3662);
PAINT MONO (-2988 3662);
FORCEPROP 1 LAST PACK_TYPE 0402LF
J 0
(-2950 3600);
DISPLAY 0.489362 (-2950 3600);
PAINT SKYBLUE (-2950 3600);
FORCEPROP 1 LAST PART_NUMBER CS00002JB38
J 0
(-3725 3600);
DISPLAY 0.489362 (-3725 3600);
PAINT SKYBLUE (-3725 3600);
FORCEPROP 1 LAST VALUE 0
J 2
(-3050 3600);
DISPLAY 0.489362 (-3050 3600);
PAINT SKYBLUE (-3050 3600);
FORCEPROP 1 LAST TOLERANCE 5%
J 0
(-3025 3600);
DISPLAY 0.489362 (-3025 3600);
PAINT SKYBLUE (-3025 3600);
FORCEPROP 1 LAST MATERIAL CHIP
J 0
(-3375 3600);
DISPLAY 0.489362 (-3375 3600);
PAINT SKYBLUE (-3375 3600);
FORCEPROP 1 LAST WATTAGE 1/16W
J 2
(-3125 3600);
DISPLAY 0.489362 (-3125 3600);
PAINT SKYBLUE (-3125 3600);
FORCEPROP 1 LAST PATH I272
J 0
(-3100 3800);
DISPLAY 0.978723 (-3100 3800);
PAINT WHITE (-3100 3800);
DISPLAY INVISIBLE (-3100 3800);
FORCEPROP 2 LAST CDS_LIB pure_quanta
J 0
(-3050 3650);
DISPLAY INVISIBLE (-3050 3650);
FORCEADD Q_RES..1
(-3050 3200);
FORCEPROP 1 LAST LOCATION PR13
J 0
(-3100 3250);
DISPLAY 0.489362 (-3100 3250);
PAINT SKYBLUE (-3100 3250);
FORCEPROP 0 LAST $SEC 1
J 0
(-3100 3300);
DISPLAY 0.680851 (-3100 3300);
PAINT MONO (-3100 3300);
DISPLAY INVISIBLE (-3100 3300);
FORCEPROP 0 LAST CDS_SEC 1
J 0
(-3100 3300);
DISPLAY 1.021277 (-3100 3300);
DISPLAY INVISIBLE (-3100 3300);
FORCEPROP 1 LASTPIN (-3150 3200) $PN 1
J 0
(-3138 3212);
DISPLAY 0.489362 (-3138 3212);
PAINT MONO (-3138 3212);
FORCEPROP 1 LASTPIN (-2950 3200) $PN 2
J 0
(-2988 3212);
DISPLAY 0.489362 (-2988 3212);
PAINT MONO (-2988 3212);
FORCEPROP 1 LAST PACK_TYPE 0402LF
J 0
(-2950 3150);
DISPLAY 0.489362 (-2950 3150);
PAINT SKYBLUE (-2950 3150);
FORCEPROP 1 LAST PART_NUMBER CS00002JB38
J 0
(-3725 3150);
DISPLAY 0.489362 (-3725 3150);
PAINT SKYBLUE (-3725 3150);
FORCEPROP 1 LAST VALUE 0
J 2
(-3050 3150);
DISPLAY 0.489362 (-3050 3150);
PAINT SKYBLUE (-3050 3150);
FORCEPROP 1 LAST TOLERANCE 5%
J 0
(-3025 3150);
DISPLAY 0.489362 (-3025 3150);
PAINT SKYBLUE (-3025 3150);
FORCEPROP 1 LAST WATTAGE 1/16W
J 2
(-3125 3150);
DISPLAY 0.489362 (-3125 3150);
PAINT SKYBLUE (-3125 3150);
FORCEPROP 1 LAST MATERIAL CHIP
J 0
(-3375 3150);
DISPLAY 0.489362 (-3375 3150);
PAINT SKYBLUE (-3375 3150);
FORCEPROP 1 LAST PATH I273
J 0
(-3100 3350);
DISPLAY 0.978723 (-3100 3350);
PAINT WHITE (-3100 3350);
DISPLAY INVISIBLE (-3100 3350);
FORCEPROP 2 LAST CDS_LIB pure_quanta
J 0
(-3050 3200);
DISPLAY INVISIBLE (-3050 3200);
FORCEADD UNIVERSAL_GND..1
(-2600 3125);
FORCEPROP 3 LASTPIN (-2600 3175) SIG_NAME GND\g
J 0
(-2590 3185);
DISPLAY 0.659574 (-2590 3185);
PAINT MONO (-2590 3185);
DISPLAY INVISIBLE (-2590 3185);
FORCEPROP 1 LAST HDL_POWER GND
J 1
(-2575 3050);
DISPLAY 0.872340 (-2575 3050);
PAINT GREEN (-2575 3050);
DISPLAY INVISIBLE (-2575 3050);
FORCEPROP 1 LAST PATH I274
J 0
(-2525 3125);
DISPLAY 0.872340 (-2525 3125);
PAINT AQUA (-2525 3125);
DISPLAY INVISIBLE (-2525 3125);
FORCEPROP 2 LAST CDS_LIB pure_quanta_power
J 0
(-2600 3125);
DISPLAY INVISIBLE (-2600 3125);
FORCEADD UNIVERSAL_GND..1
(-2600 2675);
FORCEPROP 3 LASTPIN (-2600 2725) SIG_NAME GND\g
J 0
(-2590 2735);
DISPLAY 0.659574 (-2590 2735);
PAINT MONO (-2590 2735);
DISPLAY INVISIBLE (-2590 2735);
FORCEPROP 1 LAST HDL_POWER GND
J 1
(-2575 2600);
DISPLAY 0.872340 (-2575 2600);
PAINT GREEN (-2575 2600);
DISPLAY INVISIBLE (-2575 2600);
FORCEPROP 1 LAST PATH I275
J 0
(-2525 2675);
DISPLAY 0.872340 (-2525 2675);
PAINT AQUA (-2525 2675);
DISPLAY INVISIBLE (-2525 2675);
FORCEPROP 2 LAST CDS_LIB pure_quanta_power
J 0
(-2600 2675);
DISPLAY INVISIBLE (-2600 2675);
FORCEADD UNIVERSAL_GND..1
(-2600 2225);
FORCEPROP 3 LASTPIN (-2600 2275) SIG_NAME GND\g
J 0
(-2590 2285);
DISPLAY 0.659574 (-2590 2285);
PAINT MONO (-2590 2285);
DISPLAY INVISIBLE (-2590 2285);
FORCEPROP 1 LAST HDL_POWER GND
J 1
(-2575 2150);
DISPLAY 0.872340 (-2575 2150);
PAINT GREEN (-2575 2150);
DISPLAY INVISIBLE (-2575 2150);
FORCEPROP 1 LAST PATH I276
J 0
(-2525 2225);
DISPLAY 0.872340 (-2525 2225);
PAINT AQUA (-2525 2225);
DISPLAY INVISIBLE (-2525 2225);
FORCEPROP 2 LAST CDS_LIB pure_quanta_power
J 0
(-2600 2225);
DISPLAY INVISIBLE (-2600 2225);
FORCEADD UNIVERSAL_GND..1
(-2600 1775);
FORCEPROP 3 LASTPIN (-2600 1825) SIG_NAME GND\g
J 0
(-2590 1835);
DISPLAY 0.659574 (-2590 1835);
PAINT MONO (-2590 1835);
DISPLAY INVISIBLE (-2590 1835);
FORCEPROP 1 LAST HDL_POWER GND
J 1
(-2575 1700);
DISPLAY 0.872340 (-2575 1700);
PAINT GREEN (-2575 1700);
DISPLAY INVISIBLE (-2575 1700);
FORCEPROP 1 LAST PATH I277
J 0
(-2525 1775);
DISPLAY 0.872340 (-2525 1775);
PAINT AQUA (-2525 1775);
DISPLAY INVISIBLE (-2525 1775);
FORCEPROP 2 LAST CDS_LIB pure_quanta_power
J 0
(-2600 1775);
DISPLAY INVISIBLE (-2600 1775);
FORCEADD Q_RES..1
(-3050 2750);
FORCEPROP 1 LAST LOCATION PR14
J 0
(-3100 2800);
DISPLAY 0.489362 (-3100 2800);
PAINT SKYBLUE (-3100 2800);
FORCEPROP 0 LAST $SEC 1
J 0
(-3100 2850);
DISPLAY 0.680851 (-3100 2850);
PAINT MONO (-3100 2850);
DISPLAY INVISIBLE (-3100 2850);
FORCEPROP 0 LAST CDS_SEC 1
J 0
(-3100 2850);
DISPLAY 1.021277 (-3100 2850);
DISPLAY INVISIBLE (-3100 2850);
FORCEPROP 1 LASTPIN (-3150 2750) $PN 1
J 0
(-3138 2762);
DISPLAY 0.489362 (-3138 2762);
PAINT MONO (-3138 2762);
FORCEPROP 1 LASTPIN (-2950 2750) $PN 2
J 0
(-2988 2762);
DISPLAY 0.489362 (-2988 2762);
PAINT MONO (-2988 2762);
FORCEPROP 1 LAST PACK_TYPE 0402LF
J 0
(-2950 2700);
DISPLAY 0.489362 (-2950 2700);
PAINT SKYBLUE (-2950 2700);
FORCEPROP 1 LAST PART_NUMBER CS00002JB38
J 0
(-3725 2700);
DISPLAY 0.489362 (-3725 2700);
PAINT SKYBLUE (-3725 2700);
FORCEPROP 1 LAST VALUE 0
J 2
(-3050 2700);
DISPLAY 0.489362 (-3050 2700);
PAINT SKYBLUE (-3050 2700);
FORCEPROP 1 LAST TOLERANCE 5%
J 0
(-3025 2700);
DISPLAY 0.489362 (-3025 2700);
PAINT SKYBLUE (-3025 2700);
FORCEPROP 1 LAST MATERIAL CHIP
J 0
(-3375 2700);
DISPLAY 0.489362 (-3375 2700);
PAINT SKYBLUE (-3375 2700);
FORCEPROP 1 LAST WATTAGE 1/16W
J 2
(-3125 2700);
DISPLAY 0.489362 (-3125 2700);
PAINT SKYBLUE (-3125 2700);
FORCEPROP 1 LAST PATH I278
J 0
(-3100 2900);
DISPLAY 0.978723 (-3100 2900);
PAINT WHITE (-3100 2900);
DISPLAY INVISIBLE (-3100 2900);
FORCEPROP 2 LAST CDS_LIB pure_quanta
J 0
(-3050 2750);
DISPLAY INVISIBLE (-3050 2750);
FORCEADD Q_RES..1
(-3050 2300);
FORCEPROP 1 LAST LOCATION PR408
J 0
(-3100 2350);
DISPLAY 0.489362 (-3100 2350);
PAINT SKYBLUE (-3100 2350);
FORCEPROP 0 LAST $SEC 1
J 0
(-3100 2400);
DISPLAY 0.680851 (-3100 2400);
PAINT MONO (-3100 2400);
DISPLAY INVISIBLE (-3100 2400);
FORCEPROP 0 LAST CDS_SEC 1
J 0
(-3100 2400);
DISPLAY 1.021277 (-3100 2400);
DISPLAY INVISIBLE (-3100 2400);
FORCEPROP 1 LASTPIN (-3150 2300) $PN 1
J 0
(-3138 2312);
DISPLAY 0.489362 (-3138 2312);
PAINT MONO (-3138 2312);
FORCEPROP 1 LASTPIN (-2950 2300) $PN 2
J 0
(-2988 2312);
DISPLAY 0.489362 (-2988 2312);
PAINT MONO (-2988 2312);
FORCEPROP 1 LAST PACK_TYPE 0402LF
J 0
(-2950 2250);
DISPLAY 0.489362 (-2950 2250);
PAINT SKYBLUE (-2950 2250);
FORCEPROP 1 LAST PART_NUMBER CS00002JB38
J 0
(-3725 2250);
DISPLAY 0.489362 (-3725 2250);
PAINT SKYBLUE (-3725 2250);
FORCEPROP 1 LAST VALUE 0
J 2
(-3050 2250);
DISPLAY 0.489362 (-3050 2250);
PAINT SKYBLUE (-3050 2250);
FORCEPROP 1 LAST TOLERANCE 5%
J 0
(-3025 2250);
DISPLAY 0.489362 (-3025 2250);
PAINT SKYBLUE (-3025 2250);
FORCEPROP 1 LAST MATERIAL CHIP
J 0
(-3375 2250);
DISPLAY 0.489362 (-3375 2250);
PAINT SKYBLUE (-3375 2250);
FORCEPROP 1 LAST WATTAGE 1/16W
J 2
(-3125 2250);
DISPLAY 0.489362 (-3125 2250);
PAINT SKYBLUE (-3125 2250);
FORCEPROP 1 LAST PATH I279
J 0
(-3100 2450);
DISPLAY 0.978723 (-3100 2450);
PAINT WHITE (-3100 2450);
DISPLAY INVISIBLE (-3100 2450);
FORCEPROP 2 LAST CDS_LIB pure_quanta
J 0
(-3050 2300);
DISPLAY INVISIBLE (-3050 2300);
FORCEADD Q_RES..1
(-3050 1850);
FORCEPROP 1 LAST LOCATION PR409
J 0
(-3100 1900);
DISPLAY 0.489362 (-3100 1900);
PAINT SKYBLUE (-3100 1900);
FORCEPROP 0 LAST $SEC 1
J 0
(-3100 1950);
DISPLAY 0.680851 (-3100 1950);
PAINT MONO (-3100 1950);
DISPLAY INVISIBLE (-3100 1950);
FORCEPROP 0 LAST CDS_SEC 1
J 0
(-3100 1950);
DISPLAY 1.021277 (-3100 1950);
DISPLAY INVISIBLE (-3100 1950);
FORCEPROP 1 LASTPIN (-3150 1850) $PN 1
J 0
(-3138 1862);
DISPLAY 0.489362 (-3138 1862);
PAINT MONO (-3138 1862);
FORCEPROP 1 LASTPIN (-2950 1850) $PN 2
J 0
(-2988 1862);
DISPLAY 0.489362 (-2988 1862);
PAINT MONO (-2988 1862);
FORCEPROP 1 LAST PACK_TYPE 0402LF
J 0
(-2950 1800);
DISPLAY 0.489362 (-2950 1800);
PAINT SKYBLUE (-2950 1800);
FORCEPROP 1 LAST PART_NUMBER CS00002JB38
J 0
(-3725 1800);
DISPLAY 0.489362 (-3725 1800);
PAINT SKYBLUE (-3725 1800);
FORCEPROP 1 LAST VALUE 0
J 2
(-3050 1800);
DISPLAY 0.489362 (-3050 1800);
PAINT SKYBLUE (-3050 1800);
FORCEPROP 1 LAST TOLERANCE 5%
J 0
(-3025 1800);
DISPLAY 0.489362 (-3025 1800);
PAINT SKYBLUE (-3025 1800);
FORCEPROP 1 LAST MATERIAL CHIP
J 0
(-3375 1800);
DISPLAY 0.489362 (-3375 1800);
PAINT SKYBLUE (-3375 1800);
FORCEPROP 1 LAST WATTAGE 1/16W
J 2
(-3125 1800);
DISPLAY 0.489362 (-3125 1800);
PAINT SKYBLUE (-3125 1800);
FORCEPROP 1 LAST PATH I280
J 0
(-3100 2000);
DISPLAY 0.978723 (-3100 2000);
PAINT WHITE (-3100 2000);
DISPLAY INVISIBLE (-3100 2000);
FORCEPROP 2 LAST CDS_LIB pure_quanta
J 0
(-3050 1850);
DISPLAY INVISIBLE (-3050 1850);
FORCEADD OFFPAGE..4
(-2900 5000);
FORCEPROP 2 LAST $XR0 201 
J 0
(-2714 5000);
DISPLAY 0.638298 (-2714 5000);
PAINT MONO (-2714 5000);
FORCEPROP 2 LAST PATH I281
J 0
(-2700 5050);
DISPLAY 1.021277 (-2700 5050);
DISPLAY INVISIBLE (-2700 5050);
FORCEPROP 1 LAST OFFPAGE TRUE
J 0
(-2575 4875);
DISPLAY 0.872340 (-2575 4875);
PAINT GREEN (-2575 4875);
DISPLAY INVISIBLE (-2575 4875);
FORCEPROP 2 LAST CDS_LIB standard
J 0
(-2900 5000);
DISPLAY INVISIBLE (-2900 5000);
FORCEPROP 1 LAST COMMENT_BODY TRUE
J 0
(-2925 4900);
DISPLAY 0.872340 (-2925 4900);
PAINT GREEN (-2925 4900);
DISPLAY INVISIBLE (-2925 4900);
FORCEADD OFFPAGE..2
(-2900 5100);
FORCEPROP 2 LAST $XR0 201 
J 0
(-2711 5100);
DISPLAY 0.638298 (-2711 5100);
PAINT MONO (-2711 5100);
FORCEPROP 2 LAST PATH I282
J 0
(-2700 5150);
DISPLAY 1.021277 (-2700 5150);
DISPLAY INVISIBLE (-2700 5150);
FORCEPROP 2 LAST CDS_LIB standard
J 0
(-2900 5100);
DISPLAY INVISIBLE (-2900 5100);
FORCEPROP 1 LAST OFFPAGE TRUE
J 0
(-2575 4975);
DISPLAY 0.872340 (-2575 4975);
PAINT GREEN (-2575 4975);
DISPLAY INVISIBLE (-2575 4975);
FORCEPROP 1 LAST COMMENT_BODY TRUE
J 0
(-2945 5005);
DISPLAY 0.872340 (-2945 5005);
PAINT GREEN (-2945 5005);
DISPLAY INVISIBLE (-2945 5005);
FORCEADD OFFPAGE..2
(-2900 4650);
FORCEPROP 2 LAST $XR0 201 
J 0
(-2711 4650);
DISPLAY 0.638298 (-2711 4650);
PAINT MONO (-2711 4650);
FORCEPROP 2 LAST PATH I283
J 0
(-2700 4700);
DISPLAY 1.021277 (-2700 4700);
DISPLAY INVISIBLE (-2700 4700);
FORCEPROP 1 LAST COMMENT_BODY TRUE
J 0
(-2945 4555);
DISPLAY 0.872340 (-2945 4555);
PAINT GREEN (-2945 4555);
DISPLAY INVISIBLE (-2945 4555);
FORCEPROP 1 LAST OFFPAGE TRUE
J 0
(-2575 4525);
DISPLAY 0.872340 (-2575 4525);
PAINT GREEN (-2575 4525);
DISPLAY INVISIBLE (-2575 4525);
FORCEPROP 2 LAST CDS_LIB standard
J 0
(-2900 4650);
DISPLAY INVISIBLE (-2900 4650);
FORCEADD OFFPAGE..4
(-2900 4550);
FORCEPROP 2 LAST $XR0 201 
J 0
(-2714 4550);
DISPLAY 0.638298 (-2714 4550);
PAINT MONO (-2714 4550);
FORCEPROP 2 LAST PATH I284
J 0
(-2700 4600);
DISPLAY 1.021277 (-2700 4600);
DISPLAY INVISIBLE (-2700 4600);
FORCEPROP 1 LAST COMMENT_BODY TRUE
J 0
(-2925 4450);
DISPLAY 0.872340 (-2925 4450);
PAINT GREEN (-2925 4450);
DISPLAY INVISIBLE (-2925 4450);
FORCEPROP 2 LAST CDS_LIB standard
J 0
(-2900 4550);
DISPLAY INVISIBLE (-2900 4550);
FORCEPROP 1 LAST OFFPAGE TRUE
J 0
(-2575 4425);
DISPLAY 0.872340 (-2575 4425);
PAINT GREEN (-2575 4425);
DISPLAY INVISIBLE (-2575 4425);
FORCEADD VCC_CORE..1
(-6200 725);
FORCEPROP 3 LASTPIN (-6200 675) SIG_NAME P12V_STBY\g
J 0
(-6190 685);
DISPLAY 0.659574 (-6190 685);
PAINT MONO (-6190 685);
DISPLAY INVISIBLE (-6190 685);
FORCEPROP 1 LAST HDL_POWER P12V_STBY
J 1
(-6200 775);
DISPLAY 0.489362 (-6200 775);
PAINT GREEN (-6200 775);
FORCEPROP 1 LAST PATH I285
J 0
(-6150 750);
DISPLAY 0.872340 (-6150 750);
PAINT AQUA (-6150 750);
DISPLAY INVISIBLE (-6150 750);
FORCEPROP 2 LAST CDS_LIB pure_quanta_power
J 0
(-6200 725);
DISPLAY INVISIBLE (-6200 725);
FORCEADD UNIVERSAL_GND..1
(-5650 250);
FORCEPROP 3 LASTPIN (-5650 300) SIG_NAME GND\g
J 0
(-5640 310);
DISPLAY 0.659574 (-5640 310);
PAINT MONO (-5640 310);
DISPLAY INVISIBLE (-5640 310);
FORCEPROP 1 LAST HDL_POWER GND
J 1
(-5625 175);
DISPLAY 0.872340 (-5625 175);
PAINT GREEN (-5625 175);
DISPLAY INVISIBLE (-5625 175);
FORCEPROP 1 LAST PATH I286
J 0
(-5575 250);
DISPLAY 0.872340 (-5575 250);
PAINT AQUA (-5575 250);
DISPLAY INVISIBLE (-5575 250);
FORCEPROP 2 LAST CDS_LIB pure_quanta_power
J 0
(-5650 250);
DISPLAY INVISIBLE (-5650 250);
FORCEADD Q_RES..2
(-5650 450);
FORCEPROP 1 LAST LOCATION PR604
J 0
(-5600 575);
DISPLAY 0.489362 (-5600 575);
PAINT SKYBLUE (-5600 575);
FORCEPROP 0 LAST $SEC 1
J 0
(-5600 600);
DISPLAY 0.680851 (-5600 600);
PAINT MONO (-5600 600);
DISPLAY INVISIBLE (-5600 600);
FORCEPROP 0 LAST CDS_SEC 1
J 0
(-5600 600);
DISPLAY 0.680851 (-5600 600);
DISPLAY INVISIBLE (-5600 600);
FORCEPROP 1 LASTPIN (-5650 550) $PN 1
J 0
(-5645 512);
DISPLAY 0.787234 (-5645 512);
PAINT MONO (-5645 512);
DISPLAY INVISIBLE (-5645 512);
FORCEPROP 1 LASTPIN (-5650 350) $PN 2
J 0
(-5645 360);
DISPLAY 0.787234 (-5645 360);
PAINT MONO (-5645 360);
DISPLAY INVISIBLE (-5645 360);
FORCEPROP 1 LAST PACK_TYPE 0402LF
J 0
(-5600 275);
DISPLAY 0.489362 (-5600 275);
PAINT SKYBLUE (-5600 275);
FORCEPROP 1 LAST PART_NUMBER CS24992FB07
J 0
(-5600 325);
DISPLAY 0.489362 (-5600 325);
PAINT SKYBLUE (-5600 325);
FORCEPROP 1 LAST VALUE 4.99K
J 0
(-5600 525);
DISPLAY 0.489362 (-5600 525);
PAINT SKYBLUE (-5600 525);
FORCEPROP 1 LAST TOLERANCE 1%
J 0
(-5600 475);
DISPLAY 0.489362 (-5600 475);
PAINT SKYBLUE (-5600 475);
FORCEPROP 1 LAST MATERIAL EMPTY
J 0
(-5600 375);
DISPLAY 0.489362 (-5600 375);
PAINT RED (-5600 375);
FORCEPROP 1 LAST WATTAGE 1/16W
J 0
(-5600 425);
DISPLAY 0.489362 (-5600 425);
PAINT SKYBLUE (-5600 425);
FORCEPROP 1 LAST PATH I287
J 0
(-5600 625);
DISPLAY 0.978723 (-5600 625);
PAINT WHITE (-5600 625);
DISPLAY INVISIBLE (-5600 625);
FORCEPROP 2 LAST CDS_LIB pure_quanta
J 0
(-5650 450);
DISPLAY INVISIBLE (-5650 450);
FORCEADD Q_CAP..1
(-3375 700);
FORCEPROP 1 LAST LOCATION PC643
J 0
(-3325 800);
DISPLAY 0.489362 (-3325 800);
PAINT SKYBLUE (-3325 800);
FORCEPROP 0 LAST $SEC 1
J 0
(-3325 825);
DISPLAY 0.680851 (-3325 825);
PAINT MONO (-3325 825);
DISPLAY INVISIBLE (-3325 825);
FORCEPROP 0 LAST CDS_SEC 1
J 0
(-3325 825);
DISPLAY 1.021277 (-3325 825);
DISPLAY INVISIBLE (-3325 825);
FORCEPROP 1 LASTPIN (-3375 800) $PN 1
J 0
(-3365 780);
DISPLAY 0.489362 (-3365 780);
PAINT MONO (-3365 780);
FORCEPROP 1 LASTPIN (-3375 600) $PN 2
J 0
(-3365 580);
DISPLAY 0.489362 (-3365 580);
PAINT MONO (-3365 580);
FORCEPROP 1 LAST PACK_TYPE 0402
J 0
(-3325 500);
DISPLAY 0.489362 (-3325 500);
PAINT SKYBLUE (-3325 500);
FORCEPROP 1 LAST VOLTAGE 50V
J 0
(-3325 700);
DISPLAY 0.489362 (-3325 700);
PAINT SKYBLUE (-3325 700);
FORCEPROP 1 LAST PART_NUMBER TMP_QCH14706KB18
J 0
(-3325 550);
DISPLAY 0.489362 (-3325 550);
PAINT SKYBLUE (-3325 550);
FORCEPROP 1 LAST VALUE 470PF
J 0
(-3325 750);
DISPLAY 0.489362 (-3325 750);
PAINT SKYBLUE (-3325 750);
FORCEPROP 1 LAST TOLERANCE 10%
J 0
(-3325 650);
DISPLAY 0.489362 (-3325 650);
PAINT SKYBLUE (-3325 650);
FORCEPROP 1 LAST MATERIAL X7R
J 0
(-3325 600);
DISPLAY 0.489362 (-3325 600);
PAINT SKYBLUE (-3325 600);
FORCEPROP 1 LAST PATH I36
J 0
(-3325 850);
DISPLAY 0.978723 (-3325 850);
PAINT WHITE (-3325 850);
DISPLAY INVISIBLE (-3325 850);
FORCEPROP 2 LAST CDS_LIB pure_quanta
J 0
(-3375 700);
DISPLAY INVISIBLE (-3375 700);
FORCEADD UNIVERSAL_GND..1
(-3375 425);
FORCEPROP 3 LASTPIN (-3375 475) SIG_NAME GND\g
J 0
(-3365 485);
DISPLAY 0.659574 (-3365 485);
PAINT MONO (-3365 485);
DISPLAY INVISIBLE (-3365 485);
FORCEPROP 1 LAST HDL_POWER GND
J 1
(-3350 350);
DISPLAY 0.872340 (-3350 350);
PAINT GREEN (-3350 350);
DISPLAY INVISIBLE (-3350 350);
FORCEPROP 1 LAST PATH I37
J 0
(-3300 425);
DISPLAY 0.872340 (-3300 425);
PAINT AQUA (-3300 425);
DISPLAY INVISIBLE (-3300 425);
FORCEPROP 2 LAST CDS_LIB pure_quanta_power
J 0
(-3375 425);
DISPLAY INVISIBLE (-3375 425);
FORCEADD Q_RES..1
(-5900 5950);
FORCEPROP 1 LAST LOCATION PR386
J 0
(-5950 5975);
DISPLAY 0.489362 (-5950 5975);
PAINT SKYBLUE (-5950 5975);
FORCEPROP 0 LAST $SEC 1
J 0
(-5775 6000);
DISPLAY 0.680851 (-5775 6000);
PAINT MONO (-5775 6000);
DISPLAY INVISIBLE (-5775 6000);
FORCEPROP 0 LAST CDS_SEC 1
J 0
(-5775 6000);
DISPLAY 1.021277 (-5775 6000);
DISPLAY INVISIBLE (-5775 6000);
FORCEPROP 1 LASTPIN (-6000 5950) $PN 1
J 0
(-5988 5962);
DISPLAY 0.489362 (-5988 5962);
PAINT MONO (-5988 5962);
FORCEPROP 1 LASTPIN (-5800 5950) $PN 2
J 0
(-5838 5962);
DISPLAY 0.489362 (-5838 5962);
PAINT MONO (-5838 5962);
FORCEPROP 1 LAST PACK_TYPE 0402LF
J 0
(-5800 5875);
DISPLAY 0.489362 (-5800 5875);
PAINT SKYBLUE (-5800 5875);
FORCEPROP 1 LAST PART_NUMBER CS00002JB38
J 0
(-6150 5900);
DISPLAY 0.489362 (-6150 5900);
PAINT SKYBLUE (-6150 5900);
FORCEPROP 1 LAST TOLERANCE 5%
J 0
(-5775 5975);
DISPLAY 0.489362 (-5775 5975);
PAINT SKYBLUE (-5775 5975);
FORCEPROP 1 LAST MATERIAL CHIP
J 0
(-6150 5875);
DISPLAY 0.489362 (-6150 5875);
PAINT SKYBLUE (-6150 5875);
FORCEPROP 1 LAST WATTAGE 1/16W
J 0
(-5800 5900);
DISPLAY 0.489362 (-5800 5900);
PAINT SKYBLUE (-5800 5900);
FORCEPROP 1 LAST VALUE 0
J 2
(-6025 5975);
DISPLAY 0.489362 (-6025 5975);
PAINT SKYBLUE (-6025 5975);
FORCEPROP 1 LAST PATH I47
J 0
(-5950 6100);
DISPLAY 0.978723 (-5950 6100);
PAINT WHITE (-5950 6100);
DISPLAY INVISIBLE (-5950 6100);
FORCEPROP 2 LAST CDS_LIB pure_quanta
J 0
(-5900 5950);
DISPLAY INVISIBLE (-5900 5950);
FORCEADD Q_CAP..2
(-5225 5825);
FORCEPROP 1 LAST LOCATION PC642
J 1
(-5225 5875);
DISPLAY 0.489362 (-5225 5875);
PAINT SKYBLUE (-5225 5875);
FORCEPROP 0 LAST $SEC 1
J 0
(-5225 5925);
DISPLAY 0.680851 (-5225 5925);
PAINT MONO (-5225 5925);
DISPLAY INVISIBLE (-5225 5925);
FORCEPROP 0 LAST CDS_SEC 1
J 0
(-5225 5925);
DISPLAY 1.021277 (-5225 5925);
DISPLAY INVISIBLE (-5225 5925);
FORCEPROP 1 LASTPIN (-5325 5825) $PN 1
J 0
(-5335 5840);
DISPLAY 0.489362 (-5335 5840);
PAINT MONO (-5335 5840);
FORCEPROP 1 LASTPIN (-5125 5825) $PN 2
J 0
(-5140 5840);
DISPLAY 0.489362 (-5140 5840);
PAINT MONO (-5140 5840);
FORCEPROP 1 LAST PART_NUMBER TMP_QCH21006JB10
J 0
(-5650 5800);
DISPLAY 0.489362 (-5650 5800);
PAINT SKYBLUE (-5650 5800);
FORCEPROP 1 LAST VALUE 1000PF
J 2
(-5400 5850);
DISPLAY 0.489362 (-5400 5850);
PAINT SKYBLUE (-5400 5850);
FORCEPROP 1 LAST TOLERANCE 5%
J 0
(-5125 5775);
DISPLAY 0.489362 (-5125 5775);
PAINT SKYBLUE (-5125 5775);
FORCEPROP 1 LAST MATERIAL X7R
J 0
(-5650 5775);
DISPLAY 0.489362 (-5650 5775);
PAINT SKYBLUE (-5650 5775);
FORCEPROP 1 LAST PACK_TYPE 0402
J 0
(-5125 5800);
DISPLAY 0.489362 (-5125 5800);
PAINT SKYBLUE (-5125 5800);
FORCEPROP 1 LAST VOLTAGE 50V
J 0
(-5075 5850);
DISPLAY 0.489362 (-5075 5850);
PAINT SKYBLUE (-5075 5850);
FORCEPROP 1 LAST PATH I49
J 0
(-5225 6025);
DISPLAY 0.978723 (-5225 6025);
PAINT WHITE (-5225 6025);
DISPLAY INVISIBLE (-5225 6025);
FORCEPROP 2 LAST CDS_LIB pure_quanta
J 0
(-5225 5825);
DISPLAY INVISIBLE (-5225 5825);
FORCEADD UNIVERSAL_GND..1
(-5000 5750);
FORCEPROP 3 LASTPIN (-5000 5800) SIG_NAME GND\g
J 0
(-4990 5810);
DISPLAY 0.659574 (-4990 5810);
PAINT MONO (-4990 5810);
DISPLAY INVISIBLE (-4990 5810);
FORCEPROP 1 LAST HDL_POWER GND
J 1
(-4975 5675);
DISPLAY 0.872340 (-4975 5675);
PAINT GREEN (-4975 5675);
DISPLAY INVISIBLE (-4975 5675);
FORCEPROP 1 LAST PATH I50
J 0
(-4925 5750);
DISPLAY 0.872340 (-4925 5750);
PAINT AQUA (-4925 5750);
DISPLAY INVISIBLE (-4925 5750);
FORCEPROP 2 LAST CDS_LIB pure_quanta_power
J 0
(-5000 5750);
DISPLAY INVISIBLE (-5000 5750);
FORCEADD Q_RES..1
(-5975 4950);
FORCEPROP 1 LAST LOCATION PR381
J 0
(-6025 5000);
DISPLAY 0.489362 (-6025 5000);
PAINT SKYBLUE (-6025 5000);
FORCEPROP 0 LAST $SEC 1
J 0
(-6025 5025);
DISPLAY 0.680851 (-6025 5025);
PAINT MONO (-6025 5025);
DISPLAY INVISIBLE (-6025 5025);
FORCEPROP 0 LAST CDS_SEC 1
J 0
(-6025 5025);
DISPLAY 1.021277 (-6025 5025);
DISPLAY INVISIBLE (-6025 5025);
FORCEPROP 1 LASTPIN (-6075 4950) $PN 1
J 0
(-6063 4962);
DISPLAY 0.489362 (-6063 4962);
PAINT MONO (-6063 4962);
FORCEPROP 1 LASTPIN (-5875 4950) $PN 2
J 0
(-5913 4962);
DISPLAY 0.489362 (-5913 4962);
PAINT MONO (-5913 4962);
FORCEPROP 1 LAST PACK_TYPE 0402LF
J 0
(-5875 4875);
DISPLAY 0.489362 (-5875 4875);
PAINT SKYBLUE (-5875 4875);
FORCEPROP 1 LAST PART_NUMBER CS00002JB38
J 0
(-6225 4900);
DISPLAY 0.489362 (-6225 4900);
PAINT SKYBLUE (-6225 4900);
FORCEPROP 1 LAST VALUE 0
J 2
(-6100 4975);
DISPLAY 0.489362 (-6100 4975);
PAINT SKYBLUE (-6100 4975);
FORCEPROP 1 LAST TOLERANCE 5%
J 0
(-5850 4975);
DISPLAY 0.489362 (-5850 4975);
PAINT SKYBLUE (-5850 4975);
FORCEPROP 1 LAST MATERIAL CHIP
J 0
(-6225 4875);
DISPLAY 0.489362 (-6225 4875);
PAINT SKYBLUE (-6225 4875);
FORCEPROP 1 LAST WATTAGE 1/16W
J 0
(-5875 4900);
DISPLAY 0.489362 (-5875 4900);
PAINT SKYBLUE (-5875 4900);
FORCEPROP 1 LAST PATH I66
J 0
(-6025 5100);
DISPLAY 0.978723 (-6025 5100);
PAINT WHITE (-6025 5100);
DISPLAY INVISIBLE (-6025 5100);
FORCEPROP 2 LAST CDS_LIB pure_quanta
J 0
(-5975 4950);
DISPLAY INVISIBLE (-5975 4950);
FORCEADD Q_RES..1
(-5975 4800);
FORCEPROP 1 LAST LOCATION PR382
J 0
(-6025 4850);
DISPLAY 0.489362 (-6025 4850);
PAINT SKYBLUE (-6025 4850);
FORCEPROP 0 LAST $SEC 1
J 0
(-6025 4875);
DISPLAY 0.680851 (-6025 4875);
PAINT MONO (-6025 4875);
DISPLAY INVISIBLE (-6025 4875);
FORCEPROP 0 LAST CDS_SEC 1
J 0
(-6025 4875);
DISPLAY 1.021277 (-6025 4875);
DISPLAY INVISIBLE (-6025 4875);
FORCEPROP 1 LASTPIN (-6075 4800) $PN 1
J 0
(-6063 4812);
DISPLAY 0.489362 (-6063 4812);
PAINT MONO (-6063 4812);
FORCEPROP 1 LASTPIN (-5875 4800) $PN 2
J 0
(-5913 4812);
DISPLAY 0.489362 (-5913 4812);
PAINT MONO (-5913 4812);
FORCEPROP 1 LAST PACK_TYPE 0402LF
J 0
(-5875 4725);
DISPLAY 0.489362 (-5875 4725);
PAINT SKYBLUE (-5875 4725);
FORCEPROP 1 LAST PART_NUMBER CS00002JB38
J 0
(-6225 4750);
DISPLAY 0.489362 (-6225 4750);
PAINT SKYBLUE (-6225 4750);
FORCEPROP 1 LAST VALUE 0
J 2
(-6100 4825);
DISPLAY 0.489362 (-6100 4825);
PAINT SKYBLUE (-6100 4825);
FORCEPROP 1 LAST TOLERANCE 5%
J 0
(-5850 4825);
DISPLAY 0.489362 (-5850 4825);
PAINT SKYBLUE (-5850 4825);
FORCEPROP 1 LAST MATERIAL CHIP
J 0
(-6225 4725);
DISPLAY 0.489362 (-6225 4725);
PAINT SKYBLUE (-6225 4725);
FORCEPROP 1 LAST WATTAGE 1/16W
J 0
(-5875 4750);
DISPLAY 0.489362 (-5875 4750);
PAINT SKYBLUE (-5875 4750);
FORCEPROP 1 LAST PATH I67
J 0
(-6025 4950);
DISPLAY 0.978723 (-6025 4950);
PAINT WHITE (-6025 4950);
DISPLAY INVISIBLE (-6025 4950);
FORCEPROP 2 LAST CDS_LIB pure_quanta
J 0
(-5975 4800);
DISPLAY INVISIBLE (-5975 4800);
FORCEADD Q_RES..1
(-5975 4650);
FORCEPROP 1 LAST LOCATION PR383
J 0
(-6025 4700);
DISPLAY 0.489362 (-6025 4700);
PAINT SKYBLUE (-6025 4700);
FORCEPROP 0 LAST $SEC 1
J 0
(-6025 4725);
DISPLAY 0.680851 (-6025 4725);
PAINT MONO (-6025 4725);
DISPLAY INVISIBLE (-6025 4725);
FORCEPROP 0 LAST CDS_SEC 1
J 0
(-6025 4725);
DISPLAY 1.021277 (-6025 4725);
DISPLAY INVISIBLE (-6025 4725);
FORCEPROP 1 LASTPIN (-6075 4650) $PN 1
J 0
(-6063 4662);
DISPLAY 0.489362 (-6063 4662);
PAINT MONO (-6063 4662);
FORCEPROP 1 LASTPIN (-5875 4650) $PN 2
J 0
(-5913 4662);
DISPLAY 0.489362 (-5913 4662);
PAINT MONO (-5913 4662);
FORCEPROP 1 LAST PACK_TYPE 0402LF
J 0
(-5875 4575);
DISPLAY 0.489362 (-5875 4575);
PAINT SKYBLUE (-5875 4575);
FORCEPROP 1 LAST PART_NUMBER CS00002JB38
J 0
(-6225 4600);
DISPLAY 0.489362 (-6225 4600);
PAINT SKYBLUE (-6225 4600);
FORCEPROP 1 LAST VALUE 0
J 2
(-6100 4675);
DISPLAY 0.489362 (-6100 4675);
PAINT SKYBLUE (-6100 4675);
FORCEPROP 1 LAST TOLERANCE 5%
J 0
(-5850 4675);
DISPLAY 0.489362 (-5850 4675);
PAINT SKYBLUE (-5850 4675);
FORCEPROP 1 LAST MATERIAL CHIP
J 0
(-6225 4575);
DISPLAY 0.489362 (-6225 4575);
PAINT SKYBLUE (-6225 4575);
FORCEPROP 1 LAST WATTAGE 1/16W
J 0
(-5875 4600);
DISPLAY 0.489362 (-5875 4600);
PAINT SKYBLUE (-5875 4600);
FORCEPROP 1 LAST PATH I68
J 0
(-6025 4800);
DISPLAY 0.978723 (-6025 4800);
PAINT WHITE (-6025 4800);
DISPLAY INVISIBLE (-6025 4800);
FORCEPROP 2 LAST CDS_LIB pure_quanta
J 0
(-5975 4650);
DISPLAY INVISIBLE (-5975 4650);
FORCEADD RAA229621GNPHA0..1
(-4325 3350);
FORCEPROP 1 LAST LOCATION PU54
J 0
(-4875 6375);
DISPLAY 0.489362 (-4875 6375);
PAINT SKYBLUE (-4875 6375);
FORCEPROP 0 LAST $SEC 1
J 0
(-4850 6550);
DISPLAY 0.680851 (-4850 6550);
PAINT MONO (-4850 6550);
DISPLAY INVISIBLE (-4850 6550);
FORCEPROP 0 LAST CDS_SEC 1
J 0
(-4850 6550);
DISPLAY 1.021277 (-4850 6550);
DISPLAY INVISIBLE (-4850 6550);
FORCEPROP 0 LASTPIN (-3675 1850) $PN 30
J 0
(-3665 1860);
DISPLAY 0.489362 (-3665 1860);
PAINT MONO (-3665 1860);
FORCEPROP 0 LASTPIN (-3675 2300) $PN 29
J 0
(-3665 2310);
DISPLAY 0.489362 (-3665 2310);
PAINT MONO (-3665 2310);
FORCEPROP 0 LASTPIN (-3675 2750) $PN 28
J 0
(-3665 2760);
DISPLAY 0.489362 (-3665 2760);
PAINT MONO (-3665 2760);
FORCEPROP 0 LASTPIN (-3675 3200) $PN 27
J 0
(-3665 3210);
DISPLAY 0.489362 (-3665 3210);
PAINT MONO (-3665 3210);
FORCEPROP 0 LASTPIN (-3675 3650) $PN 26
J 0
(-3665 3660);
DISPLAY 0.489362 (-3665 3660);
PAINT MONO (-3665 3660);
FORCEPROP 0 LASTPIN (-3675 4100) $PN 25
J 0
(-3665 4110);
DISPLAY 0.489362 (-3665 4110);
PAINT MONO (-3665 4110);
FORCEPROP 0 LASTPIN (-3675 4550) $PN 24
J 0
(-3665 4560);
DISPLAY 0.489362 (-3665 4560);
PAINT MONO (-3665 4560);
FORCEPROP 0 LASTPIN (-3675 5000) $PN 23
J 0
(-3665 5010);
DISPLAY 0.489362 (-3665 5010);
PAINT MONO (-3665 5010);
FORCEPROP 0 LASTPIN (-5025 5950) $PN 13
J 2
(-5035 5960);
DISPLAY 0.489362 (-5035 5960);
PAINT MONO (-5035 5960);
FORCEPROP 0 LASTPIN (-5025 1400) $PN 34
J 2
(-5035 1410);
DISPLAY 0.489362 (-5035 1410);
PAINT MONO (-5035 1410);
FORCEPROP 0 LASTPIN (-5025 4650) $PN 11
J 2
(-5035 4660);
DISPLAY 0.489362 (-5035 4660);
PAINT MONO (-5035 4660);
FORCEPROP 0 LASTPIN (-5025 2100) $PN 33
J 2
(-5035 2110);
DISPLAY 0.489362 (-5035 2110);
PAINT MONO (-5035 2110);
FORCEPROP 0 LASTPIN (-5025 6100) $PN 12
J 2
(-5035 6110);
DISPLAY 0.489362 (-5035 6110);
PAINT MONO (-5035 6110);
FORCEPROP 0 LASTPIN (-5025 850) $PN 16
J 2
(-5035 860);
DISPLAY 0.489362 (-5035 860);
PAINT MONO (-5035 860);
FORCEPROP 0 LASTPIN (-5025 4950) $PN 10
J 2
(-5035 4960);
DISPLAY 0.489362 (-5035 4960);
PAINT MONO (-5035 4960);
FORCEPROP 0 LASTPIN (-5025 4800) $PN 9
J 2
(-5035 4810);
DISPLAY 0.489362 (-5035 4810);
PAINT MONO (-5035 4810);
FORCEPROP 0 LASTPIN (-3675 1950) $PN 1
J 0
(-3665 1960);
DISPLAY 0.489362 (-3665 1960);
PAINT MONO (-3665 1960);
FORCEPROP 0 LASTPIN (-3675 2400) $PN 2
J 0
(-3665 2410);
DISPLAY 0.489362 (-3665 2410);
PAINT MONO (-3665 2410);
FORCEPROP 0 LASTPIN (-3675 2850) $PN 3
J 0
(-3665 2860);
DISPLAY 0.489362 (-3665 2860);
PAINT MONO (-3665 2860);
FORCEPROP 0 LASTPIN (-3675 3300) $PN 4
J 0
(-3665 3310);
DISPLAY 0.489362 (-3665 3310);
PAINT MONO (-3665 3310);
FORCEPROP 0 LASTPIN (-3675 3750) $PN 5
J 0
(-3665 3760);
DISPLAY 0.489362 (-3665 3760);
PAINT MONO (-3665 3760);
FORCEPROP 0 LASTPIN (-3675 4200) $PN 6
J 0
(-3665 4210);
DISPLAY 0.489362 (-3665 4210);
PAINT MONO (-3665 4210);
FORCEPROP 0 LASTPIN (-3675 4650) $PN 7
J 0
(-3665 4660);
DISPLAY 0.489362 (-3665 4660);
PAINT MONO (-3665 4660);
FORCEPROP 0 LASTPIN (-3675 5100) $PN 8
J 0
(-3665 5110);
DISPLAY 0.489362 (-3665 5110);
PAINT MONO (-3665 5110);
FORCEPROP 0 LASTPIN (-3675 1600) $PN 14
J 0
(-3665 1610);
DISPLAY 0.489362 (-3665 1610);
PAINT MONO (-3665 1610);
FORCEPROP 0 LASTPIN (-5025 3800) $PN 22
J 2
(-5035 3810);
DISPLAY 0.489362 (-5035 3810);
PAINT MONO (-5035 3810);
FORCEPROP 0 LASTPIN (-5025 2700) $PN 31
J 2
(-5035 2710);
DISPLAY 0.489362 (-5035 2710);
PAINT MONO (-5035 2710);
FORCEPROP 0 LASTPIN (-5025 5650) $PN 18
J 2
(-5035 5660);
DISPLAY 0.489362 (-5035 5660);
PAINT MONO (-5035 5660);
FORCEPROP 0 LASTPIN (-5025 5500) $PN 17
J 2
(-5035 5510);
DISPLAY 0.489362 (-5035 5510);
PAINT MONO (-5035 5510);
FORCEPROP 0 LASTPIN (-5025 5200) $PN 20
J 2
(-5035 5210);
DISPLAY 0.489362 (-5035 5210);
PAINT MONO (-5035 5210);
FORCEPROP 0 LASTPIN (-5025 5350) $PN 19
J 2
(-5035 5360);
DISPLAY 0.489362 (-5035 5360);
PAINT MONO (-5035 5360);
FORCEPROP 0 LASTPIN (-3675 900) $PN 36
J 0
(-3665 910);
DISPLAY 0.489362 (-3665 910);
PAINT MONO (-3665 910);
FORCEPROP 0 LASTPIN (-3675 1200) $PN 35
J 0
(-3665 1210);
DISPLAY 0.489362 (-3665 1210);
PAINT MONO (-3665 1210);
FORCEPROP 0 LASTPIN (-5025 550) $PN TH
J 2
(-5035 560);
DISPLAY 0.489362 (-5035 560);
PAINT MONO (-5035 560);
FORCEPROP 0 LASTPIN (-3675 6100) $PN 39
J 0
(-3665 6110);
DISPLAY 0.489362 (-3665 6110);
PAINT MONO (-3665 6110);
FORCEPROP 0 LASTPIN (-3675 5800) $PN 40
J 0
(-3665 5810);
DISPLAY 0.489362 (-3665 5810);
PAINT MONO (-3665 5810);
FORCEPROP 0 LASTPIN (-5025 1850) $PN 15
J 2
(-5035 1860);
DISPLAY 0.489362 (-5035 1860);
PAINT MONO (-5035 1860);
FORCEPROP 0 LASTPIN (-5025 650) $PN 38
J 2
(-5035 660);
DISPLAY 0.489362 (-5035 660);
PAINT MONO (-5035 660);
FORCEPROP 0 LASTPIN (-5025 750) $PN 37
J 2
(-5035 760);
DISPLAY 0.489362 (-5035 760);
PAINT MONO (-5035 760);
FORCEPROP 0 LASTPIN (-5025 4050) $PN 21
J 2
(-5035 4060);
DISPLAY 0.489362 (-5035 4060);
PAINT MONO (-5035 4060);
FORCEPROP 0 LASTPIN (-5025 2950) $PN 32
J 2
(-5035 2960);
DISPLAY 0.489362 (-5035 2960);
PAINT MONO (-5035 2960);
FORCEPROP 1 LAST MATERIAL IC
J 0
(-4875 6225);
DISPLAY 0.489362 (-4875 6225);
PAINT SKYBLUE (-4875 6225);
FORCEPROP 1 LAST PART_NUMBER AR0T6GPV006
J 0
(-4875 6300);
DISPLAY 0.489362 (-4875 6300);
PAINT SKYBLUE (-4875 6300);
FORCEPROP 2 LAST PART_TYPE SMLF
J 0
(-4875 6500);
DISPLAY 1.021277 (-4875 6500);
FORCEPROP 2 LAST VALUE RAA229621GNP#HA0
J 0
(-4875 6450);
DISPLAY 0.489362 (-4875 6450);
PAINT SKYBLUE (-4875 6450);
FORCEPROP 1 LAST NEEDS_NO_SIZE TRUE
J 0
(-4325 3350);
DISPLAY 0.723404 (-4325 3350);
PAINT GREEN (-4325 3350);
DISPLAY INVISIBLE (-4325 3350);
FORCEPROP 2 LAST CDS_LIB pure_quanta
J 0
(-4325 3350);
DISPLAY INVISIBLE (-4325 3350);
FORCEPROP 1 LAST CDS_LMAN_SYM_OUTLINE -550,2850,500,-2850
J 0
(-4325 3350);
DISPLAY 0.468085 (-4325 3350);
PAINT GREEN (-4325 3350);
DISPLAY INVISIBLE (-4325 3350);
FORCEPROP 1 LAST PATH I7
J 0
(-4325 3350);
DISPLAY 0.723404 (-4325 3350);
PAINT GREEN (-4325 3350);
DISPLAY INVISIBLE (-4325 3350);
FORCEADD OFFPAGE..2
R 2
(-6750 4950);
FORCEPROP 2 LAST $XR1 176 
J 0
(-7125 4950);
DISPLAY 0.638298 (-7125 4950);
PAINT MONO (-7125 4950);
FORCEPROP 2 LAST $XR0 118 
J 0
(-7005 4950);
DISPLAY 0.638298 (-7005 4950);
PAINT MONO (-7005 4950);
FORCEPROP 2 LAST PATH I73
J 0
(-6700 5025);
DISPLAY 1.021277 (-6700 5025);
DISPLAY INVISIBLE (-6700 5025);
FORCEPROP 2 LAST CDS_LIB standard
J 0
(-6750 4950);
DISPLAY INVISIBLE (-6750 4950);
FORCEPROP 1 LAST COMMENT_BODY TRUE
J 2
(-6705 4855);
DISPLAY 0.872340 (-6705 4855);
PAINT GREEN (-6705 4855);
DISPLAY INVISIBLE (-6705 4855);
FORCEPROP 1 LAST OFFPAGE TRUE
J 2
(-7075 4825);
DISPLAY 0.872340 (-7075 4825);
PAINT GREEN (-7075 4825);
DISPLAY INVISIBLE (-7075 4825);
FORCEADD OFFPAGE..2
R 2
(-6750 4800);
FORCEPROP 2 LAST $XR1 176 
J 0
(-7125 4800);
DISPLAY 0.638298 (-7125 4800);
PAINT MONO (-7125 4800);
FORCEPROP 2 LAST $XR0 118 
J 0
(-7005 4800);
DISPLAY 0.638298 (-7005 4800);
PAINT MONO (-7005 4800);
FORCEPROP 2 LAST PATH I74
J 0
(-6700 4875);
DISPLAY 1.021277 (-6700 4875);
DISPLAY INVISIBLE (-6700 4875);
FORCEPROP 2 LAST CDS_LIB standard
J 0
(-6750 4800);
DISPLAY INVISIBLE (-6750 4800);
FORCEPROP 1 LAST COMMENT_BODY TRUE
J 2
(-6705 4705);
DISPLAY 0.872340 (-6705 4705);
PAINT GREEN (-6705 4705);
DISPLAY INVISIBLE (-6705 4705);
FORCEPROP 1 LAST OFFPAGE TRUE
J 2
(-7075 4675);
DISPLAY 0.872340 (-7075 4675);
PAINT GREEN (-7075 4675);
DISPLAY INVISIBLE (-7075 4675);
FORCEADD OFFPAGE..2
R 2
(-6750 4650);
FORCEPROP 2 LAST $XR1 81 
J 0
(-7064 4650);
DISPLAY 0.638298 (-7064 4650);
PAINT MONO (-7064 4650);
FORCEPROP 2 LAST $XR0 82 
J 0
(-6974 4650);
DISPLAY 0.638298 (-6974 4650);
PAINT MONO (-6974 4650);
FORCEPROP 2 LAST PATH I75
J 0
(-6700 4725);
DISPLAY 1.021277 (-6700 4725);
DISPLAY INVISIBLE (-6700 4725);
FORCEPROP 2 LAST CDS_LIB standard
J 0
(-6750 4650);
DISPLAY INVISIBLE (-6750 4650);
FORCEPROP 1 LAST COMMENT_BODY TRUE
J 2
(-6705 4555);
DISPLAY 0.872340 (-6705 4555);
PAINT GREEN (-6705 4555);
DISPLAY INVISIBLE (-6705 4555);
FORCEPROP 1 LAST OFFPAGE TRUE
J 2
(-7075 4525);
DISPLAY 0.872340 (-7075 4525);
PAINT GREEN (-7075 4525);
DISPLAY INVISIBLE (-7075 4525);
FORCEADD Q_CAP..1
(-5675 3925);
FORCEPROP 1 LAST LOCATION PC639
J 0
(-5625 3975);
DISPLAY 0.489362 (-5625 3975);
PAINT SKYBLUE (-5625 3975);
FORCEPROP 0 LAST $SEC 1
J 0
(-5625 4000);
DISPLAY 0.680851 (-5625 4000);
PAINT MONO (-5625 4000);
DISPLAY INVISIBLE (-5625 4000);
FORCEPROP 0 LAST CDS_SEC 1
J 0
(-5625 4000);
DISPLAY 1.021277 (-5625 4000);
DISPLAY INVISIBLE (-5625 4000);
FORCEPROP 1 LASTPIN (-5675 4025) $PN 1
J 0
(-5665 4005);
DISPLAY 0.489362 (-5665 4005);
PAINT MONO (-5665 4005);
FORCEPROP 1 LASTPIN (-5675 3825) $PN 2
J 0
(-5665 3805);
DISPLAY 0.489362 (-5665 3805);
PAINT MONO (-5665 3805);
FORCEPROP 1 LAST PACK_TYPE 0402
J 0
(-5625 3825);
DISPLAY 0.489362 (-5625 3825);
PAINT SKYBLUE (-5625 3825);
FORCEPROP 1 LAST VOLTAGE 50V
J 0
(-5625 3925);
DISPLAY 0.489362 (-5625 3925);
PAINT SKYBLUE (-5625 3925);
FORCEPROP 1 LAST PART_NUMBER TMP_QCH2336K1B12
J 0
(-5625 3850);
DISPLAY 0.489362 (-5625 3850);
PAINT SKYBLUE (-5625 3850);
FORCEPROP 1 LAST VALUE 3300PF
J 0
(-5625 3950);
DISPLAY 0.489362 (-5625 3950);
PAINT SKYBLUE (-5625 3950);
FORCEPROP 1 LAST TOLERANCE 10%
J 0
(-5625 3900);
DISPLAY 0.489362 (-5625 3900);
PAINT SKYBLUE (-5625 3900);
FORCEPROP 1 LAST MATERIAL X7R
J 0
(-5625 3875);
DISPLAY 0.489362 (-5625 3875);
PAINT SKYBLUE (-5625 3875);
FORCEPROP 1 LAST PATH I76
J 0
(-5625 4075);
DISPLAY 0.978723 (-5625 4075);
PAINT WHITE (-5625 4075);
DISPLAY INVISIBLE (-5625 4075);
FORCEPROP 2 LAST CDS_LIB pure_quanta
J 0
(-5675 3925);
DISPLAY INVISIBLE (-5675 3925);
FORCEADD Q_RES..1
(-5975 4050);
FORCEPROP 1 LAST LOCATION PR384
J 0
(-6025 4100);
DISPLAY 0.489362 (-6025 4100);
PAINT SKYBLUE (-6025 4100);
FORCEPROP 0 LAST $SEC 1
J 0
(-6025 4125);
DISPLAY 0.680851 (-6025 4125);
PAINT MONO (-6025 4125);
DISPLAY INVISIBLE (-6025 4125);
FORCEPROP 0 LAST CDS_SEC 1
J 0
(-6025 4125);
DISPLAY 1.021277 (-6025 4125);
DISPLAY INVISIBLE (-6025 4125);
FORCEPROP 1 LASTPIN (-6075 4050) $PN 1
J 0
(-6063 4062);
DISPLAY 0.489362 (-6063 4062);
PAINT MONO (-6063 4062);
FORCEPROP 1 LASTPIN (-5875 4050) $PN 2
J 0
(-5913 4062);
DISPLAY 0.489362 (-5913 4062);
PAINT MONO (-5913 4062);
FORCEPROP 1 LAST PACK_TYPE 0402LF
J 0
(-5875 3975);
DISPLAY 0.489362 (-5875 3975);
PAINT SKYBLUE (-5875 3975);
FORCEPROP 1 LAST PART_NUMBER TMP_QCS01002FB21
J 0
(-6300 4000);
DISPLAY 0.489362 (-6300 4000);
PAINT SKYBLUE (-6300 4000);
FORCEPROP 1 LAST VALUE 10
J 2
(-6100 4075);
DISPLAY 0.489362 (-6100 4075);
PAINT SKYBLUE (-6100 4075);
FORCEPROP 1 LAST TOLERANCE 1%
J 0
(-5850 4075);
DISPLAY 0.489362 (-5850 4075);
PAINT SKYBLUE (-5850 4075);
FORCEPROP 1 LAST MATERIAL CHIP
J 0
(-6300 3975);
DISPLAY 0.489362 (-6300 3975);
PAINT SKYBLUE (-6300 3975);
FORCEPROP 1 LAST WATTAGE 1/16W
J 0
(-5875 4000);
DISPLAY 0.489362 (-5875 4000);
PAINT SKYBLUE (-5875 4000);
FORCEPROP 1 LAST PATH I77
J 0
(-6025 4200);
DISPLAY 0.978723 (-6025 4200);
PAINT WHITE (-6025 4200);
DISPLAY INVISIBLE (-6025 4200);
FORCEPROP 2 LAST CDS_LIB pure_quanta
J 0
(-5975 4050);
DISPLAY INVISIBLE (-5975 4050);
FORCEADD OFFPAGE..4
R 2
(-7475 4050);
FORCEPROP 2 LAST $XR0 54 
J 0
(-7816 4050);
DISPLAY 0.638298 (-7816 4050);
PAINT MONO (-7816 4050);
FORCEPROP 2 LAST PATH I79
J 2
(-7650 4125);
DISPLAY 1.021277 (-7650 4125);
DISPLAY INVISIBLE (-7650 4125);
FORCEPROP 1 LAST COMMENT_BODY TRUE
J 2
(-7450 3950);
DISPLAY 0.872340 (-7450 3950);
PAINT GREEN (-7450 3950);
DISPLAY INVISIBLE (-7450 3950);
FORCEPROP 2 LAST CDS_LIB standard
J 2
(-7475 4050);
DISPLAY INVISIBLE (-7475 4050);
FORCEPROP 1 LAST OFFPAGE TRUE
J 2
(-7800 3925);
DISPLAY 0.872340 (-7800 3925);
PAINT GREEN (-7800 3925);
DISPLAY INVISIBLE (-7800 3925);
FORCEADD Q_CAP..1
(-2925 6125);
FORCEPROP 1 LAST LOCATION PC645
J 0
(-2875 6225);
DISPLAY 0.489362 (-2875 6225);
PAINT SKYBLUE (-2875 6225);
FORCEPROP 0 LAST $SEC 1
J 0
(-2875 6250);
DISPLAY 0.680851 (-2875 6250);
PAINT MONO (-2875 6250);
DISPLAY INVISIBLE (-2875 6250);
FORCEPROP 0 LAST CDS_SEC 1
J 0
(-2875 6250);
DISPLAY 1.021277 (-2875 6250);
DISPLAY INVISIBLE (-2875 6250);
FORCEPROP 1 LASTPIN (-2925 6225) $PN 1
J 0
(-2915 6205);
DISPLAY 0.489362 (-2915 6205);
PAINT MONO (-2915 6205);
FORCEPROP 1 LASTPIN (-2925 6025) $PN 2
J 0
(-2915 6005);
DISPLAY 0.489362 (-2915 6005);
PAINT MONO (-2915 6005);
FORCEPROP 1 LAST PACK_TYPE C0402
J 0
(-2875 5925);
DISPLAY 0.489362 (-2875 5925);
PAINT SKYBLUE (-2875 5925);
FORCEPROP 1 LAST VOLTAGE 16V
J 0
(-2875 6125);
DISPLAY 0.489362 (-2875 6125);
PAINT SKYBLUE (-2875 6125);
FORCEPROP 1 LAST PART_NUMBER CH5103KEB01
J 0
(-2875 5975);
DISPLAY 0.489362 (-2875 5975);
PAINT SKYBLUE (-2875 5975);
FORCEPROP 1 LAST VALUE 1UF
J 0
(-2875 6175);
DISPLAY 0.489362 (-2875 6175);
PAINT SKYBLUE (-2875 6175);
FORCEPROP 1 LAST TOLERANCE 10%
J 0
(-2875 6075);
DISPLAY 0.489362 (-2875 6075);
PAINT SKYBLUE (-2875 6075);
FORCEPROP 1 LAST MATERIAL X6S
J 0
(-2875 6025);
DISPLAY 0.489362 (-2875 6025);
PAINT SKYBLUE (-2875 6025);
FORCEPROP 1 LAST PATH I8
J 0
(-2875 6275);
DISPLAY 0.978723 (-2875 6275);
PAINT WHITE (-2875 6275);
DISPLAY INVISIBLE (-2875 6275);
FORCEPROP 2 LAST CDS_LIB pure_quanta
J 0
(-2925 6125);
DISPLAY INVISIBLE (-2925 6125);
FORCEADD OFFPAGE..4
R 2
(-7475 3800);
FORCEPROP 2 LAST $XR1 193 
J 0
(-7936 3800);
DISPLAY 0.638298 (-7936 3800);
PAINT MONO (-7936 3800);
FORCEPROP 2 LAST $XR0 54 
J 0
(-7816 3800);
DISPLAY 0.638298 (-7816 3800);
PAINT MONO (-7816 3800);
FORCEPROP 2 LAST PATH I80
J 0
(-7425 3875);
DISPLAY 1.021277 (-7425 3875);
DISPLAY INVISIBLE (-7425 3875);
FORCEPROP 2 LAST CDS_LIB standard
J 0
(-7475 3800);
DISPLAY INVISIBLE (-7475 3800);
FORCEPROP 1 LAST COMMENT_BODY TRUE
J 2
(-7450 3700);
DISPLAY 0.872340 (-7450 3700);
PAINT GREEN (-7450 3700);
DISPLAY INVISIBLE (-7450 3700);
FORCEPROP 1 LAST OFFPAGE TRUE
J 2
(-7800 3675);
DISPLAY 0.872340 (-7800 3675);
PAINT GREEN (-7800 3675);
DISPLAY INVISIBLE (-7800 3675);
FORCEADD UNIVERSAL_GND..1
(-5100 450);
FORCEPROP 3 LASTPIN (-5100 500) SIG_NAME GND\g
J 0
(-5090 510);
DISPLAY 0.659574 (-5090 510);
PAINT MONO (-5090 510);
DISPLAY INVISIBLE (-5090 510);
FORCEPROP 1 LAST HDL_POWER GND
J 1
(-5075 375);
DISPLAY 0.872340 (-5075 375);
PAINT GREEN (-5075 375);
DISPLAY INVISIBLE (-5075 375);
FORCEPROP 1 LAST PATH I99
J 0
(-5025 450);
DISPLAY 0.872340 (-5025 450);
PAINT AQUA (-5025 450);
DISPLAY INVISIBLE (-5025 450);
FORCEPROP 2 LAST CDS_LIB pure_quanta_power
J 0
(-5100 450);
DISPLAY INVISIBLE (-5100 450);
FORCEADD DNS..1
(-6125 1725);
PAINT RED (-6125 1725);
FORCEPROP 1 LAST COMMENT_BODY TRUE
R 1
J 0
(-6050 1500);
DISPLAY 0.872340 (-6050 1500);
PAINT GREEN (-6050 1500);
DISPLAY INVISIBLE (-6050 1500);
FORCEPROP 2 LAST CDS_LIB mstr_misc
J 0
(-6125 1725);
DISPLAY INVISIBLE (-6125 1725);
FORCEADD DNS..1
(-5625 450);
PAINT RED (-5625 450);
FORCEPROP 1 LAST COMMENT_BODY TRUE
R 1
J 0
(-5550 225);
DISPLAY 0.872340 (-5550 225);
PAINT GREEN (-5550 225);
DISPLAY INVISIBLE (-5550 225);
FORCEPROP 2 LAST CDS_LIB mstr_misc
J 0
(-5625 450);
DISPLAY INVISIBLE (-5625 450);
FORCEADD DNS..1
(-5250 6350);
PAINT RED (-5250 6350);
FORCEPROP 1 LAST COMMENT_BODY TRUE
R 1
J 0
(-5175 6125);
DISPLAY 0.872340 (-5175 6125);
PAINT GREEN (-5175 6125);
DISPLAY INVISIBLE (-5175 6125);
FORCEPROP 2 LAST CDS_LIB mstr_misc
J 0
(-5250 6350);
DISPLAY INVISIBLE (-5250 6350);
FORCEADD DNS..1
(-1625 1800);
PAINT RED (-1625 1800);
FORCEPROP 1 LAST COMMENT_BODY TRUE
R 1
J 0
(-1550 1575);
DISPLAY 0.872340 (-1550 1575);
PAINT GREEN (-1550 1575);
DISPLAY INVISIBLE (-1550 1575);
FORCEPROP 2 LAST CDS_LIB mstr_misc
J 0
(-1625 1800);
DISPLAY INVISIBLE (-1625 1800);
FORCEADD DNS..1
(-2050 1375);
PAINT RED (-2050 1375);
FORCEPROP 1 LAST COMMENT_BODY TRUE
R 1
J 0
(-1975 1150);
DISPLAY 0.872340 (-1975 1150);
PAINT GREEN (-1975 1150);
DISPLAY INVISIBLE (-1975 1150);
FORCEPROP 2 LAST CDS_LIB mstr_misc
J 0
(-2050 1375);
DISPLAY INVISIBLE (-2050 1375);
FORCEADD DNS..1
(-1575 1575);
PAINT RED (-1575 1575);
FORCEPROP 1 LAST COMMENT_BODY TRUE
R 1
J 0
(-1500 1350);
DISPLAY 0.872340 (-1500 1350);
PAINT GREEN (-1500 1350);
DISPLAY INVISIBLE (-1500 1350);
FORCEPROP 2 LAST CDS_LIB mstr_misc
J 0
(-1575 1575);
DISPLAY INVISIBLE (-1575 1575);
FORCEADD DNS..1
(-6175 2075);
PAINT RED (-6175 2075);
FORCEPROP 1 LAST COMMENT_BODY TRUE
R 1
J 0
(-6100 1850);
DISPLAY 0.872340 (-6100 1850);
PAINT GREEN (-6100 1850);
DISPLAY INVISIBLE (-6100 1850);
FORCEPROP 2 LAST CDS_LIB mstr_misc
J 0
(-6175 2075);
DISPLAY INVISIBLE (-6175 2075);
FORCEADD QUANTA_TITLE_BLOCK_C..1
(0 0);
FORCEPROP 0 LAST CDS_CON_LAST_MODIFIED Fri Mar 11 14:53:38 2022
J 0
(-1885 15);
DISPLAY INVISIBLE (-1885 15);
FORCEPROP 1 LAST CUSTOM_TXT_CDS <CON_LAST_MODIFIED>
J 0
(-1885 15);
DISPLAY 0.978723 (-1885 15);
FORCEPROP 2 LAST CUSTOM_TXT_CDS <XR_PAGE_TITLE>
J 0
(-7890 5250);
DISPLAY 0.638298 (-7890 5250);
PAINT PINK (-7890 5250);
DISPLAY INVISIBLE (-7890 5250);
FORCEPROP 1 LAST CUSTOM_TXT_CDS <NAME_2>
J 0
(-3175 50);
FORCEPROP 1 LAST CUSTOM_TXT_CDS <NAME_1>
J 0
(-3175 175);
FORCEPROP 1 LAST CUSTOM_TXT_CDS <Q_NUMBER>
J 0
(-1403 103);
DISPLAY 1.212766 (-1403 103);
FORCEPROP 1 LAST CUSTOM_TXT_CDS <Q_PROJ>
J 0
(-2382 102);
DISPLAY 1.212766 (-2382 102);
FORCEPROP 1 LAST CUSTOM_TXT_CDS <Q_REV>
J 0
(-184 103);
DISPLAY 1.212766 (-184 103);
FORCEPROP 1 LAST CUSTOM_TXT_CDS <CON_PAGE_NUM> OF <CON_TOTAL_PAGES>
J 0
(-446 18);
DISPLAY 0.978723 (-446 18);
FORCEPROP 1 LAST Q_DEPT BU9
J 1
(-3763 49);
DISPLAY 1.957447 (-3763 49);
PAINT GREEN (-3763 49);
FORCEPROP 1 LAST Q_TITLE PVDD11_S3_P1 VR CONTROLLER
J 0
(-9325 25);
DISPLAY 2.446809 (-9325 25);
PAINT GREEN (-9325 25);
FORCEPROP 1 LAST COMMENT_BODY TRUE
J 0
(12 -13);
DISPLAY 0.978723 (12 -13);
PAINT GREEN (12 -13);
DISPLAY INVISIBLE (12 -13);
FORCEPROP 1 LAST CDS_LMAN_SYM_OUTLINE -9475,6775,100,-125
J 0
(0 0);
DISPLAY 0.468085 (0 0);
PAINT GREEN (0 0);
DISPLAY INVISIBLE (0 0);
FORCEPROP 2 LAST CDS_LIB pure_quanta
J 0
(0 0);
DISPLAY INVISIBLE (0 0);
FORCEPROP 2 LAST PAGE_BORDER TRUE
J 0
(-7890 5250);
DISPLAY 0.638298 (-7890 5250);
PAINT PINK (-7890 5250);
DISPLAY INVISIBLE (-7890 5250);
FORCEPROP 2 LAST CDS_XR_PAGE_TITLE CR-200 : @T6G_MB_LIB.T6G(SCH_1):PAGE200
J 0
(-7890 5250);
DISPLAY 0.638298 (-7890 5250);
PAINT PINK (-7890 5250);
DISPLAY INVISIBLE (-7890 5250);
FORCEADD DNS..1
(-5900 2300);
PAINT RED (-5900 2300);
FORCEPROP 1 LAST COMMENT_BODY TRUE
R 1
J 0
(-5825 2075);
DISPLAY 0.872340 (-5825 2075);
PAINT GREEN (-5825 2075);
DISPLAY INVISIBLE (-5825 2075);
FORCEPROP 2 LAST CDS_LIB mstr_misc
J 0
(-5900 2300);
DISPLAY INVISIBLE (-5900 2300);
WIRE 16 -1 (-2925 5975)(-2925 6025);
WIRE 16 -1 (-5325 375)(-5325 300);
WIRE 16 -1 (-6450 550)(-6450 425);
WIRE 16 -1 (-6875 550)(-6875 450);
WIRE 16 -1 (-2925 5475)(-2925 5550);
WIRE 16 -1 (-3300 5550)(-3300 5475);
WIRE 16 -1 (-3300 6025)(-3300 5925);
WIRE 16 -1 (-2600 1200)(-2600 1175);
WIRE 16 -1 (-2950 1200)(-2600 1200);
WIRE 16 -1 (-2050 1300)(-2050 1225);
WIRE 16 -1 (-5900 2425)(-5900 2475);
WIRE 16 -1 (-6675 4325)(-6675 4375);
WIRE 16 -1 (-6675 3550)(-6675 3525);
WIRE 16 -1 (-5925 1400)(-6100 1400);
WIRE 16 -1 (-6100 1400)(-6100 1175);
WIRE 16 -1 (-2950 4100)(-2600 4100);
WIRE 16 -1 (-2600 4100)(-2600 4075);
WIRE 16 -1 (-2600 3650)(-2600 3625);
WIRE 16 -1 (-2950 3650)(-2600 3650);
WIRE 16 -1 (-2600 3200)(-2600 3175);
WIRE 16 -1 (-2950 3200)(-2600 3200);
WIRE 16 -1 (-2600 2750)(-2600 2725);
WIRE 16 -1 (-2950 2750)(-2600 2750);
WIRE 16 -1 (-2600 2300)(-2600 2275);
WIRE 16 -1 (-2950 2300)(-2600 2300);
WIRE 16 -1 (-2600 1850)(-2600 1825);
WIRE 16 -1 (-2950 1850)(-2600 1850);
WIRE 16 -1 (-5650 350)(-5650 300);
WIRE 16 -1 (-3375 600)(-3375 475);
WIRE 16 -1 (-5675 3825)(-5675 3800);
WIRE 16 -1 (-5675 3800)(-5025 3800);
WIRE 16 -1 (-6675 3800)(-5675 3800);
WIRE 16 -1 (-7425 3800)(-6675 3800);
FORCEPROP 2 LAST SIG_NAME VSENSE_VSS_SENSE_C_P1
J 2
(-6835 3810);
DISPLAY 0.489362 (-6835 3810);
WIRE 16 -1 (-6675 3750)(-6675 3800);
WIRE 16 -1 (-6675 4125)(-6675 4050);
WIRE 16 -1 (-6075 4050)(-6675 4050);
WIRE 16 -1 (-6675 4050)(-7425 4050);
FORCEPROP 2 LAST SIG_NAME VSENSE_PVDD11_S3_P1_DP
J 2
(-6835 4060);
DISPLAY 0.489362 (-6835 4060);
WIRE 17 273 (-1675 6600)(-1675 5650);
WIRE 17 273 (-1675 6600)(-100 6600);
WIRE 17 273 (-1675 5650)(-100 5650);
WIRE 17 273 (-100 6600)(-100 5650);
WIRE 16 -1 (-2925 6225)(-2925 6275);
WIRE 16 -1 (-2600 6275)(-2925 6275);
WIRE 16 -1 (-3300 6275)(-2925 6275);
FORCEPROP 2 LAST SIG_NAME PVDD11_S3_P1_VCC
J 2
(-2960 6300);
DISPLAY 0.489362 (-2960 6300);
FORCEPROP 2 LASTPROP $XRERR UNIQUE?
J 0
(-3200 6300);
DISPLAY 0.638298 (-3200 6300);
PAINT MONO (-3200 6300);
DISPLAY INVISIBLE (-3200 6300);
WIRE 16 -1 (-3300 6275)(-3300 6225);
WIRE 16 -1 (-3450 6275)(-3300 6275);
WIRE 16 -1 (-3450 6100)(-3450 6275);
WIRE 16 -1 (-3675 6100)(-3450 6100);
WIRE 16 -1 (-3675 5100)(-2950 5100);
FORCEPROP 2 LAST SIG_NAME PVDD11_S3_P1_PWM1
J 0
(-3485 5110);
DISPLAY 0.489362 (-3485 5110);
WIRE 16 -1 (-2950 5000)(-3675 5000);
FORCEPROP 2 LAST SIG_NAME PVDD11_S3_P1_IMON1
J 0
(-3485 5010);
DISPLAY 0.489362 (-3485 5010);
WIRE 16 -1 (-3675 5800)(-3300 5800);
WIRE 16 -1 (-3300 5800)(-2925 5800);
FORCEPROP 2 LAST SIG_NAME PVDD11_S3_P1_VCCS
J 2
(-2960 5810);
DISPLAY 0.489362 (-2960 5810);
WIRE 16 -1 (-3300 5800)(-3300 5750);
WIRE 16 -1 (-2775 5800)(-2925 5800);
WIRE 16 -1 (-2925 5750)(-2925 5800);
WIRE 16 -1 (-725 1600)(-1475 1600);
FORCEPROP 2 LAST SIG_NAME PVDD11_S3_P1_RESET_N
J 2
(-735 1610);
DISPLAY 0.489362 (-735 1610);
WIRE 16 -1 (-3675 2850)(-2850 2850);
FORCEPROP 2 LAST SIG_NAME NC_PVDD11_S3_P1_PWM6
J 2
(-3110 2860);
DISPLAY 0.489362 (-3110 2860);
FORCEPROP 2 LASTPROP $XRERR UNIQUE?
J 0
(-2820 2850);
DISPLAY 0.638298 (-2820 2850);
PAINT MONO (-2820 2850);
DISPLAY INVISIBLE (-2820 2850);
WIRE 16 -1 (-3675 2400)(-2850 2400);
FORCEPROP 2 LAST SIG_NAME NC_PVDD11_S3_P1_PWM7
J 2
(-3110 2410);
DISPLAY 0.489362 (-3110 2410);
FORCEPROP 2 LASTPROP $XRERR UNIQUE?
J 0
(-2820 2400);
DISPLAY 0.638298 (-2820 2400);
PAINT MONO (-2820 2400);
DISPLAY INVISIBLE (-2820 2400);
WIRE 16 -1 (-3150 3650)(-3675 3650);
FORCEPROP 2 LAST SIG_NAME NC_PVDD11_S3_P1_IMON4
J 2
(-3135 3660);
DISPLAY 0.489362 (-3135 3660);
FORCEPROP 2 LASTPROP $XRERR UNIQUE?
J 0
(-3375 3660);
DISPLAY 0.638298 (-3375 3660);
PAINT MONO (-3375 3660);
DISPLAY INVISIBLE (-3375 3660);
WIRE 16 -1 (-3150 2300)(-3675 2300);
FORCEPROP 2 LAST SIG_NAME NC_PVDD11_S3_P1_IMON7
J 2
(-3135 2310);
DISPLAY 0.489362 (-3135 2310);
FORCEPROP 2 LASTPROP $XRERR UNIQUE?
J 0
(-3375 2310);
DISPLAY 0.638298 (-3375 2310);
PAINT MONO (-3375 2310);
DISPLAY INVISIBLE (-3375 2310);
WIRE 16 -1 (-3150 2750)(-3675 2750);
FORCEPROP 2 LAST SIG_NAME NC_PVDD11_S3_P1_IMON6
J 2
(-3135 2760);
DISPLAY 0.489362 (-3135 2760);
FORCEPROP 2 LASTPROP $XRERR UNIQUE?
J 0
(-3375 2760);
DISPLAY 0.638298 (-3375 2760);
PAINT MONO (-3375 2760);
DISPLAY INVISIBLE (-3375 2760);
WIRE 16 -1 (-3675 1950)(-2850 1950);
FORCEPROP 2 LAST SIG_NAME NC_PVDD11_S3_P1_PWM8
J 2
(-3110 1960);
DISPLAY 0.489362 (-3110 1960);
FORCEPROP 2 LASTPROP $XRERR UNIQUE?
J 0
(-2820 1950);
DISPLAY 0.638298 (-2820 1950);
PAINT MONO (-2820 1950);
DISPLAY INVISIBLE (-2820 1950);
WIRE 16 -1 (-3150 1850)(-3675 1850);
FORCEPROP 2 LAST SIG_NAME NC_PVDD11_S3_P1_IMON8
J 2
(-3135 1860);
DISPLAY 0.489362 (-3135 1860);
FORCEPROP 2 LASTPROP $XRERR UNIQUE?
J 0
(-3375 1860);
DISPLAY 0.638298 (-3375 1860);
PAINT MONO (-3375 1860);
DISPLAY INVISIBLE (-3375 1860);
WIRE 16 -1 (-3150 1200)(-3675 1200);
FORCEPROP 2 LAST SIG_NAME PVDD11_S3_P1_TEMP1
J 2
(-3160 1210);
DISPLAY 0.489362 (-3160 1210);
FORCEPROP 2 LASTPROP $XRERR UNIQUE?
J 0
(-3400 1210);
DISPLAY 0.638298 (-3400 1210);
PAINT MONO (-3400 1210);
DISPLAY INVISIBLE (-3400 1210);
WIRE 16 -1 (-3100 900)(-3375 900);
FORCEPROP 2 LAST SIG_NAME PVDD11_S3_P1_TEMP0
J 2
(-3160 910);
DISPLAY 0.489362 (-3160 910);
WIRE 16 -1 (-3375 800)(-3375 900);
WIRE 16 -1 (-3375 900)(-3675 900);
WIRE 16 -1 (-5025 4800)(-5875 4800);
FORCEPROP 2 LAST SIG_NAME PVDD11_S3_P1_PMSDA_R
J 2
(-5160 4810);
DISPLAY 0.489362 (-5160 4810);
FORCEPROP 2 LASTPROP $XRERR UNIQUE?
J 0
(-5400 4810);
DISPLAY 0.638298 (-5400 4810);
PAINT MONO (-5400 4810);
DISPLAY INVISIBLE (-5400 4810);
WIRE 16 -1 (-5025 4950)(-5875 4950);
FORCEPROP 2 LAST SIG_NAME PVDD11_S3_P1_PMSCL_R
J 2
(-5160 4960);
DISPLAY 0.489362 (-5160 4960);
FORCEPROP 2 LASTPROP $XRERR UNIQUE?
J 0
(-5400 4960);
DISPLAY 0.638298 (-5400 4960);
PAINT MONO (-5400 4960);
DISPLAY INVISIBLE (-5400 4960);
WIRE 16 -1 (-6075 4650)(-6700 4650);
FORCEPROP 2 LAST SIG_NAME PVDD11_S3_P1_PMALERT
J 0
(-6675 4660);
DISPLAY 0.489362 (-6675 4660);
WIRE 16 -1 (-6700 4800)(-6075 4800);
FORCEPROP 2 LAST SIG_NAME SMB_SCM_6_R1_SDA
J 0
(-6675 4810);
DISPLAY 0.489362 (-6675 4810);
WIRE 16 -1 (-6700 4950)(-6075 4950);
FORCEPROP 2 LAST SIG_NAME SMB_SCM_6_R1_SCL
J 0
(-6675 4960);
DISPLAY 0.489362 (-6675 4960);
WIRE 16 -1 (-6000 6100)(-6675 6100);
FORCEPROP 2 LAST SIG_NAME PWRGD_PVDD11_S3_P1
J 2
(-6185 6110);
DISPLAY 0.489362 (-6185 6110);
WIRE 17 273 (-7725 4200)(-7400 4200);
WIRE 17 273 (-7725 3650)(-7725 4200);
WIRE 17 273 (-7400 4200)(-7400 3650);
WIRE 17 273 (-7725 3650)(-7400 3650);
WIRE 16 -1 (-5900 2225)(-5900 2100);
WIRE 16 -1 (-5025 2100)(-5900 2100);
FORCEPROP 2 LAST SIG_NAME PVDD11_S3_P1_OCP_N_R
J 2
(-5135 2110);
DISPLAY 0.489362 (-5135 2110);
FORCEPROP 2 LASTPROP $XRERR UNIQUE?
J 0
(-5375 2110);
DISPLAY 0.638298 (-5375 2110);
PAINT MONO (-5375 2110);
DISPLAY INVISIBLE (-5375 2110);
WIRE 16 -1 (-6075 2100)(-5900 2100);
WIRE 16 -1 (-5025 850)(-5475 850);
FORCEPROP 2 LAST SIG_NAME NC_PVDD11_S3_P1_PG1
J 0
(-5485 860);
DISPLAY 0.489362 (-5485 860);
FORCEPROP 2 LASTPROP $XRERR UNIQUE?
J 0
(-5715 850);
DISPLAY 0.638298 (-5715 850);
PAINT MONO (-5715 850);
DISPLAY INVISIBLE (-5715 850);
WIRE 16 -1 (-5325 575)(-5325 650);
WIRE 16 -1 (-5025 650)(-5325 650);
FORCEPROP 2 LAST SIG_NAME PVDD11_S3_P1_VINSEN
J 2
(-5135 660);
DISPLAY 0.489362 (-5135 660);
FORCEPROP 2 LASTPROP $XRERR UNIQUE?
J 0
(-5375 660);
DISPLAY 0.638298 (-5375 660);
PAINT MONO (-5375 660);
DISPLAY INVISIBLE (-5375 660);
WIRE 16 -1 (-5650 650)(-5325 650);
WIRE 16 -1 (-5650 550)(-5650 650);
WIRE 16 -1 (-5875 650)(-5650 650);
WIRE 16 -1 (-5675 4025)(-5675 4050);
WIRE 16 -1 (-5675 4050)(-5025 4050);
FORCEPROP 2 LAST SIG_NAME VSENSE_PVDD11_S3_P1_R
J 2
(-5135 4060);
DISPLAY 0.489362 (-5135 4060);
FORCEPROP 2 LASTPROP $XRERR UNIQUE?
J 0
(-5375 4060);
DISPLAY 0.638298 (-5375 4060);
PAINT MONO (-5375 4060);
DISPLAY INVISIBLE (-5375 4060);
WIRE 16 -1 (-5875 4050)(-5675 4050);
WIRE 16 -1 (-3150 4100)(-3675 4100);
FORCEPROP 2 LAST SIG_NAME NC_PVDD11_S3_P1_IMON3
J 2
(-3135 4110);
DISPLAY 0.489362 (-3135 4110);
FORCEPROP 2 LASTPROP $XRERR UNIQUE?
J 0
(-3375 4110);
DISPLAY 0.638298 (-3375 4110);
PAINT MONO (-3375 4110);
DISPLAY INVISIBLE (-3375 4110);
WIRE 16 -1 (-3675 4200)(-2850 4200);
FORCEPROP 2 LAST SIG_NAME NC_PVDD11_S3_P1_PWM3
J 2
(-3110 4210);
DISPLAY 0.489362 (-3110 4210);
FORCEPROP 2 LASTPROP $XRERR UNIQUE?
J 0
(-2820 4200);
DISPLAY 0.638298 (-2820 4200);
PAINT MONO (-2820 4200);
DISPLAY INVISIBLE (-2820 4200);
WIRE 16 -1 (-5875 4650)(-5025 4650);
FORCEPROP 2 LAST SIG_NAME PVDD11_S3_P1_PMALERT_R
J 2
(-5110 4660);
DISPLAY 0.489362 (-5110 4660);
FORCEPROP 2 LASTPROP $XRERR UNIQUE?
J 0
(-5350 4660);
DISPLAY 0.638298 (-5350 4660);
PAINT MONO (-5350 4660);
DISPLAY INVISIBLE (-5350 4660);
WIRE 16 -1 (-3675 1600)(-2050 1600);
FORCEPROP 2 LAST SIG_NAME PVDD11_S3_P1_RESET_N_R
J 2
(-2060 1610);
DISPLAY 0.489362 (-2060 1610);
FORCEPROP 2 LASTPROP $XRERR UNIQUE?
J 0
(-2300 1610);
DISPLAY 0.638298 (-2300 1610);
PAINT MONO (-2300 1610);
DISPLAY INVISIBLE (-2300 1610);
WIRE 16 -1 (-2050 1600)(-1950 1600);
WIRE 16 -1 (-2050 1600)(-2050 1500);
WIRE 16 -1 (-1950 1600)(-1675 1600);
WIRE 16 -1 (-1950 1600)(-1950 1825);
WIRE 16 -1 (-1950 1825)(-1725 1825);
WIRE 16 -1 (-6275 2100)(-6875 2100);
FORCEPROP 2 LAST SIG_NAME PVDD11_S3_P1_OCP_N
J 2
(-6410 2110);
DISPLAY 0.489362 (-6410 2110);
WIRE 16 -1 (-5025 1850)(-5750 1850);
FORCEPROP 2 LAST SIG_NAME PVDD11_S3_P1_VDDIO
J 2
(-5135 1860);
DISPLAY 0.489362 (-5135 1860);
FORCEPROP 2 LASTPROP $XRERR UNIQUE?
J 0
(-5375 1860);
DISPLAY 0.638298 (-5375 1860);
PAINT MONO (-5375 1860);
DISPLAY INVISIBLE (-5375 1860);
WIRE 16 -1 (-5750 1700)(-5750 1850);
WIRE 16 -1 (-6000 1700)(-5750 1700);
WIRE 16 -1 (-5625 750)(-5025 750);
FORCEPROP 2 LAST SIG_NAME PVDD11_S3_P1_VMON
J 2
(-5160 760);
DISPLAY 0.489362 (-5160 760);
FORCEPROP 2 LASTPROP $XRERR UNIQUE?
J 0
(-5400 760);
DISPLAY 0.638298 (-5400 760);
PAINT MONO (-5400 760);
DISPLAY INVISIBLE (-5400 760);
WIRE 16 -1 (-5625 825)(-5625 750);
WIRE 16 -1 (-5625 825)(-6450 825);
WIRE 16 -1 (-6450 750)(-6450 825);
WIRE 16 -1 (-6875 825)(-6450 825);
WIRE 16 -1 (-6875 750)(-6875 825);
WIRE 16 -1 (-7100 825)(-6875 825);
WIRE 17 273 (-9075 625)(-7850 625);
WIRE 17 273 (-9075 625)(-9075 200);
WIRE 17 273 (-7850 625)(-7850 200);
WIRE 17 273 (-9075 200)(-7850 200);
WIRE 16 -1 (-5725 1400)(-5025 1400);
FORCEPROP 2 LAST SIG_NAME PVDD11_S3_P1_ADDR_CFG
J 2
(-5110 1410);
DISPLAY 0.489362 (-5110 1410);
FORCEPROP 2 LASTPROP $XRERR UNIQUE?
J 0
(-5350 1410);
DISPLAY 0.638298 (-5350 1410);
PAINT MONO (-5350 1410);
DISPLAY INVISIBLE (-5350 1410);
WIRE 16 -1 (-3675 3750)(-2850 3750);
FORCEPROP 2 LAST SIG_NAME NC_PVDD11_S3_P1_PWM4
J 2
(-3110 3760);
DISPLAY 0.489362 (-3110 3760);
FORCEPROP 2 LASTPROP $XRERR UNIQUE?
J 0
(-2820 3750);
DISPLAY 0.638298 (-2820 3750);
PAINT MONO (-2820 3750);
DISPLAY INVISIBLE (-2820 3750);
WIRE 16 -1 (-3150 3200)(-3675 3200);
FORCEPROP 2 LAST SIG_NAME NC_PVDD11_S3_P1_IMON5
J 2
(-3135 3210);
DISPLAY 0.489362 (-3135 3210);
FORCEPROP 2 LASTPROP $XRERR UNIQUE?
J 0
(-3375 3210);
DISPLAY 0.638298 (-3375 3210);
PAINT MONO (-3375 3210);
DISPLAY INVISIBLE (-3375 3210);
WIRE 16 -1 (-3675 3300)(-2850 3300);
FORCEPROP 2 LAST SIG_NAME NC_PVDD11_S3_P1_PWM5
J 2
(-3110 3310);
DISPLAY 0.489362 (-3110 3310);
FORCEPROP 2 LASTPROP $XRERR UNIQUE?
J 0
(-2820 3300);
DISPLAY 0.638298 (-2820 3300);
PAINT MONO (-2820 3300);
DISPLAY INVISIBLE (-2820 3300);
WIRE 16 -1 (-6000 5950)(-6675 5950);
FORCEPROP 2 LAST SIG_NAME PVDD11_S3_P1_EN
J 2
(-6260 5960);
DISPLAY 0.489362 (-6260 5960);
WIRE 16 -1 (-5000 5800)(-5000 5825);
WIRE 16 -1 (-5000 5825)(-5125 5825);
WIRE 16 -1 (-5100 500)(-5100 550);
WIRE 16 -1 (-5100 550)(-5025 550);
WIRE 16 -1 (-6200 675)(-6200 650);
WIRE 16 -1 (-6075 650)(-6200 650);
WIRE 16 -1 (-6525 1775)(-6525 1700);
WIRE 16 -1 (-6525 1700)(-6200 1700);
WIRE 16 -1 (-1275 1925)(-1275 1825);
WIRE 16 -1 (-1275 1825)(-1525 1825);
WIRE 16 -1 (-5000 6350)(-5000 6375);
WIRE 16 -1 (-5000 6375)(-5150 6375);
WIRE 16 -1 (-6525 6450)(-6525 6375);
WIRE 16 -1 (-6525 6375)(-6225 6375);
WIRE 16 -1 (-5025 2950)(-5300 2950);
WIRE 16 -1 (-5300 2950)(-5300 2700);
WIRE 16 -1 (-5300 2600)(-5300 2700);
WIRE 16 -1 (-5300 2700)(-5025 2700);
WIRE 16 -1 (-2125 6325)(-2125 6275);
WIRE 16 -1 (-2125 6275)(-2400 6275);
WIRE 16 -1 (-7550 875)(-7550 825);
WIRE 16 -1 (-7550 825)(-7300 825);
WIRE 16 -1 (-5625 6375)(-5625 6100);
WIRE 16 -1 (-5625 6375)(-5350 6375);
WIRE 16 -1 (-6025 6375)(-5625 6375);
WIRE 16 -1 (-5625 6100)(-5025 6100);
FORCEPROP 2 LAST SIG_NAME PWRGD_PVDD11_S3_P1_R
J 2
(-5135 6110);
DISPLAY 0.489362 (-5135 6110);
FORCEPROP 2 LASTPROP $XRERR UNIQUE?
J 0
(-5375 6110);
DISPLAY 0.638298 (-5375 6110);
PAINT MONO (-5375 6110);
DISPLAY INVISIBLE (-5375 6110);
WIRE 16 -1 (-5625 6100)(-5800 6100);
WIRE 16 -1 (-5325 5825)(-5625 5825);
WIRE 16 -1 (-5625 5825)(-5625 5950);
WIRE 16 -1 (-5625 5950)(-5025 5950);
FORCEPROP 2 LAST SIG_NAME PVDD11_S3_P1_EN_R
J 2
(-5135 5960);
DISPLAY 0.489362 (-5135 5960);
FORCEPROP 2 LASTPROP $XRERR UNIQUE?
J 0
(-5375 5960);
DISPLAY 0.638298 (-5375 5960);
PAINT MONO (-5375 5960);
DISPLAY INVISIBLE (-5375 5960);
WIRE 16 -1 (-5800 5950)(-5625 5950);
WIRE 16 -1 (-5975 5150)(-5975 5200);
WIRE 16 -1 (-5975 5200)(-5025 5200);
WIRE 16 -1 (-5975 5500)(-5975 5200);
WIRE 16 -1 (-5975 5500)(-5025 5500);
WIRE 16 -1 (-5975 5650)(-5975 5500);
WIRE 16 -1 (-5025 5650)(-5975 5650);
WIRE 16 -1 (-5025 5350)(-5725 5350);
FORCEPROP 2 LAST SIG_NAME NC_PVDD11_S3_P1_SVTO
J 2
(-5210 5360);
DISPLAY 0.489362 (-5210 5360);
FORCEPROP 2 LASTPROP $XRERR UNIQUE?
J 0
(-5965 5350);
DISPLAY 0.638298 (-5965 5350);
PAINT MONO (-5965 5350);
DISPLAY INVISIBLE (-5965 5350);
WIRE 16 -1 (-2950 4550)(-3675 4550);
FORCEPROP 2 LAST SIG_NAME PVDD11_S3_P1_IMON2
J 0
(-3485 4560);
DISPLAY 0.489362 (-3485 4560);
WIRE 16 -1 (-3675 4650)(-2950 4650);
FORCEPROP 2 LAST SIG_NAME PVDD11_S3_P1_PWM2
J 0
(-3485 4660);
DISPLAY 0.489362 (-3485 4660);
DOT 1 (-6875 825);
DOT 1 (-6450 825);
DOT 1 (-6675 3800);
DOT 1 (-6675 4050);
DOT 1 (-5900 2100);
DOT 1 (-5300 2700);
DOT 1 (-5675 3800);
DOT 1 (-5675 4050);
DOT 1 (-5975 5200);
DOT 1 (-5975 5500);
DOT 1 (-5625 5950);
DOT 1 (-5625 6375);
DOT 1 (-3375 900);
DOT 1 (-2050 1600);
DOT 1 (-3300 5800);
DOT 1 (-2925 5800);
DOT 1 (-3300 6275);
DOT 1 (-2925 6275);
DOT 1 (-5325 650);
DOT 1 (-5650 650);
DOT 1 (-1950 1600);
DOT 1 (-5625 6100);
FORCENOTE
/27K
(-8200 250) 0;
DISPLAY LEFT (-8200 250);
DISPLAY 0.638298 (-8200 250);
PAINT WHITE (-8200 250);
FORCENOTE
/3.57K
(-8200 350) 0;
DISPLAY LEFT (-8200 350);
DISPLAY 0.638298 (-8200 350);
PAINT WHITE (-8200 350);
FORCENOTE
0X4A
(-8550 350) 0;
DISPLAY LEFT (-8550 350);
DISPLAY 0.638298 (-8550 350);
PAINT WHITE (-8550 350);
FORCENOTE
0X4A
(-8550 250) 0;
DISPLAY LEFT (-8550 250);
DISPLAY 0.638298 (-8550 250);
PAINT WHITE (-8550 250);
FORCENOTE
MPS
(-9000 250) 0;
DISPLAY LEFT (-9000 250);
DISPLAY 0.638298 (-9000 250);
PAINT WHITE (-9000 250);
FORCENOTE
INFINEON
(-9000 350) 0;
DISPLAY LEFT (-9000 350);
DISPLAY 0.638298 (-9000 350);
PAINT WHITE (-9000 350);
FORCENOTE
0/13.7K
(-8200 450) 0;
DISPLAY LEFT (-8200 450);
DISPLAY 0.638298 (-8200 450);
PAINT WHITE (-8200 450);
FORCENOTE
0X75
(-8550 450) 0;
DISPLAY LEFT (-8550 450);
DISPLAY 0.638298 (-8550 450);
PAINT WHITE (-8550 450);
FORCENOTE
RENESAS
(-9000 450) 0;
DISPLAY LEFT (-9000 450);
DISPLAY 0.638298 (-9000 450);
PAINT WHITE (-9000 450);
FORCENOTE
VR
(-9000 550) 0;
DISPLAY LEFT (-9000 550);
DISPLAY 0.808511 (-9000 550);
PAINT WHITE (-9000 550);
FORCENOTE
CONFIG/R
(-8200 550) 0;
DISPLAY LEFT (-8200 550);
DISPLAY 0.808511 (-8200 550);
PAINT WHITE (-8200 550);
FORCENOTE
PMBUS ADDRESS AND CONFIG
(-9100 675) 0;
DISPLAY LEFT (-9100 675);
DISPLAY 1.170213 (-9100 675);
PAINT WHITE (-9100 675);
FORCENOTE
MAIN SOURCE:RENESAS BOM
(-2000 4800) 0;
DISPLAY LEFT (-2000 4800);
DISPLAY 1.021277 (-2000 4800);
PAINT WHITE (-2000 4800);
FORCENOTE
DIFFERENTIAL PAIR
(-7775 3550) 0;
DISPLAY LEFT (-7775 3550);
DISPLAY 0.808511 (-7775 3550);
PAINT WHITE (-7775 3550);
FORCENOTE
BOM NOTE
(-2000 4900) 0;
DISPLAY LEFT (-2000 4900);
DISPLAY 1.021277 (-2000 4900);
PAINT WHITE (-2000 4900);
FORCENOTE
TRACE WIDTH = 10MIL
(-7775 3475) 0;
DISPLAY LEFT (-7775 3475);
DISPLAY 0.808511 (-7775 3475);
PAINT WHITE (-7775 3475);
FORCENOTE
TRACE SPACING = 5MIL
(-7775 3400) 0;
DISPLAY LEFT (-7775 3400);
DISPLAY 0.808511 (-7775 3400);
PAINT WHITE (-7775 3400);
FORCENOTE
EFFICIENCY > 90% @TDC
(-1650 5725) 0;
DISPLAY LEFT (-1650 5725);
DISPLAY 0.936170 (-1650 5725);
PAINT WHITE (-1650 5725);
FORCENOTE
WORK FREQUENCY=600KHZ
(-1650 5800) 0;
DISPLAY LEFT (-1650 5800);
DISPLAY 0.936170 (-1650 5800);
PAINT WHITE (-1650 5800);
FORCENOTE
ADDRESS
(-8550 550) 0;
DISPLAY LEFT (-8550 550);
DISPLAY 0.808511 (-8550 550);
PAINT WHITE (-8550 550);
FORCENOTE
OCP=96A (EDC*1.2)
(-1650 6025) 0;
DISPLAY LEFT (-1650 6025);
DISPLAY 0.936170 (-1650 6025);
PAINT WHITE (-1650 6025);
FORCENOTE
LOAD RELEASE=35A
(-1650 5875) 0;
DISPLAY LEFT (-1650 5875);
DISPLAY 0.936170 (-1650 5875);
PAINT WHITE (-1650 5875);
FORCENOTE
EDC=80A
(-1650 6100) 0;
DISPLAY LEFT (-1650 6100);
DISPLAY 0.936170 (-1650 6100);
PAINT WHITE (-1650 6100);
FORCENOTE
LOAD STEP=25A
(-1650 5950) 0;
DISPLAY LEFT (-1650 5950);
DISPLAY 0.936170 (-1650 5950);
PAINT WHITE (-1650 5950);
FORCENOTE
RIPPLE=+/-10MV
(-1650 6325) 0;
DISPLAY LEFT (-1650 6325);
DISPLAY 0.936170 (-1650 6325);
PAINT WHITE (-1650 6325);
FORCENOTE
DC & AC=1.055-1.145V
(-1650 6250) 0;
DISPLAY LEFT (-1650 6250);
DISPLAY 0.936170 (-1650 6250);
PAINT WHITE (-1650 6250);
FORCENOTE
PVDD11_S3_P1 SPECFICATION
(-1650 6525) 0;
DISPLAY LEFT (-1650 6525);
DISPLAY 1.276596 (-1650 6525);
PAINT WHITE (-1650 6525);
FORCENOTE
OUTPUT VOLTAGE=1.1V+/-4%
(-1650 6400) 0;
DISPLAY LEFT (-1650 6400);
DISPLAY 0.936170 (-1650 6400);
PAINT WHITE (-1650 6400);
FORCENOTE
TDC=65A
(-1650 6175) 0;
DISPLAY LEFT (-1650 6175);
DISPLAY 0.936170 (-1650 6175);
PAINT WHITE (-1650 6175);
FORCENOTE
PR6=CS00002JB38
(-2000 3375) 0;
DISPLAY LEFT (-2000 3375);
DISPLAY 1.021277 (-2000 3375);
PAINT WHITE (-2000 3375);
FORCENOTE
PC639,PR376,PC638=EMPTY
(-2000 3450) 0;
DISPLAY LEFT (-2000 3450);
DISPLAY 1.021277 (-2000 3450);
PAINT WHITE (-2000 3450);
FORCENOTE
PC644 = CH5103KEB01
(-2000 4350) 0;
DISPLAY LEFT (-2000 4350);
DISPLAY 1.021277 (-2000 4350);
PAINT WHITE (-2000 4350);
FORCENOTE
PR464=CS23572FB00
(-2000 4425) 0;
DISPLAY LEFT (-2000 4425);
DISPLAY 1.021277 (-2000 4425);
PAINT WHITE (-2000 4425);
FORCENOTE
PU54=AR0T6GPV006
(-2000 4725) 0;
DISPLAY LEFT (-2000 4725);
DISPLAY 1.021277 (-2000 4725);
PAINT WHITE (-2000 4725);
FORCENOTE
2ND SOURCE:INFENEON BOM
(-2000 4575) 0;
DISPLAY LEFT (-2000 4575);
DISPLAY 1.021277 (-2000 4575);
PAINT WHITE (-2000 4575);
FORCENOTE
PU54=AR0T6GPV007
(-2000 4500) 0;
DISPLAY LEFT (-2000 4500);
DISPLAY 1.021277 (-2000 4500);
PAINT WHITE (-2000 4500);
FORCENOTE
3RD SOURCE:MPS BOM
(-2000 3750) 0;
DISPLAY LEFT (-2000 3750);
DISPLAY 1.021277 (-2000 3750);
PAINT WHITE (-2000 3750);
FORCENOTE
PC643=TMP_QCH31004KB17
(-2000 3075) 0;
DISPLAY LEFT (-2000 3075);
DISPLAY 1.021277 (-2000 3075);
PAINT WHITE (-2000 3075);
FORCENOTE
PC8=TMP_QCH21006JB10
(-2000 3150) 0;
DISPLAY LEFT (-2000 3150);
DISPLAY 1.021277 (-2000 3150);
PAINT WHITE (-2000 3150);
FORCENOTE
PR604=CS24992FB07
(-2000 3225) 0;
DISPLAY LEFT (-2000 3225);
DISPLAY 1.021277 (-2000 3225);
PAINT WHITE (-2000 3225);
FORCENOTE
PR388=CS37502FB05
(-2000 3300) 0;
DISPLAY LEFT (-2000 3300);
DISPLAY 1.021277 (-2000 3300);
PAINT WHITE (-2000 3300);
FORCENOTE
PR408,PR409,PR415 = EMPTY
(-2000 3900) 0;
DISPLAY LEFT (-2000 3900);
DISPLAY 1.021277 (-2000 3900);
PAINT WHITE (-2000 3900);
FORCENOTE
PR14,PR13,PR406,PR407 = EMPTY
(-2000 3975) 0;
DISPLAY LEFT (-2000 3975);
DISPLAY 1.021277 (-2000 3975);
PAINT WHITE (-2000 3975);
FORCENOTE
PR6 = CS21002FB24
(-2000 4050) 0;
DISPLAY LEFT (-2000 4050);
DISPLAY 1.021277 (-2000 4050);
PAINT WHITE (-2000 4050);
FORCENOTE
PC639 = CH12206KB14
(-2000 4200) 0;
DISPLAY LEFT (-2000 4200);
DISPLAY 1.021277 (-2000 4200);
PAINT WHITE (-2000 4200);
FORCENOTE
PC643 = CH11006JB00
(-2000 4275) 0;
DISPLAY LEFT (-2000 4275);
DISPLAY 1.021277 (-2000 4275);
PAINT WHITE (-2000 4275);
FORCENOTE
PR376 = CS25362FB15
(-2000 4125) 0;
DISPLAY LEFT (-2000 4125);
DISPLAY 1.021277 (-2000 4125);
PAINT WHITE (-2000 4125);
FORCENOTE
PU54=AL002856000
(-2000 3675) 0;
DISPLAY LEFT (-2000 3675);
DISPLAY 1.021277 (-2000 3675);
PAINT WHITE (-2000 3675);
FORCENOTE
PR464=CS32702FB03
(-2000 3600) 0;
DISPLAY LEFT (-2000 3600);
DISPLAY 1.021277 (-2000 3600);
PAINT WHITE (-2000 3600);
FORCENOTE
PR13,PR14,PR406,PR407,PR408,PR409=EMPTY
(-2000 3525) 0;
DISPLAY LEFT (-2000 3525);
DISPLAY 1.021277 (-2000 3525);
PAINT WHITE (-2000 3525);
FORCENOTE
PC638 = CH3104J1B00
(-2000 3825) 0;
DISPLAY LEFT (-2000 3825);
DISPLAY 1.021277 (-2000 3825);
PAINT WHITE (-2000 3825);
QUIT
